FILE_TYPE = MACRO_DRAWING;
SET COLOR_WIRE YELLOW;
SET COLOR_PROP ORANGE;
SET COLOR_DOT WHITE;
SET COLOR_ARC YELLOW;
SET COLOR_BODY GREEN;
SET COLOR_NOTE PURPLE;
SET PROP_DISPLAY VALUE;
SET PAGE_NUMBER P256;
FORCEADD Q_RES..2
(2525 2700);
FORCEPROP 1 LAST LOCATION R2926
J 0
(2570 2825);
DISPLAY 0.978723 (2570 2825);
FORCEPROP 0 LAST $SEC 1
J 0
(2575 2875);
DISPLAY 0.680851 (2575 2875);
PAINT MONO (2575 2875);
DISPLAY INVISIBLE (2575 2875);
FORCEPROP 0 LAST CDS_SEC 1
J 0
(2575 2875);
DISPLAY 1.021277 (2575 2875);
DISPLAY INVISIBLE (2575 2875);
FORCEPROP 1 LASTPIN (2525 2800) $PN 1
J 0
(2530 2762);
DISPLAY 0.787234 (2530 2762);
PAINT MONO (2530 2762);
FORCEPROP 1 LASTPIN (2525 2600) $PN 2
J 0
(2530 2610);
DISPLAY 0.787234 (2530 2610);
PAINT MONO (2530 2610);
FORCEPROP 1 LAST TOLERANCE 5%
J 0
(2570 2725);
DISPLAY 0.638298 (2570 2725);
FORCEPROP 1 LAST WATTAGE 1/16W
J 0
(2565 2675);
DISPLAY 0.638298 (2565 2675);
FORCEPROP 1 LAST VALUE 4.7K
J 0
(2570 2775);
DISPLAY 0.638298 (2570 2775);
FORCEPROP 1 LAST MATERIAL CHIP
J 0
(2565 2625);
DISPLAY 0.638298 (2565 2625);
FORCEPROP 1 LAST PACK_TYPE 0402LF
J 0
(2565 2575);
DISPLAY 0.638298 (2565 2575);
FORCEPROP 1 LAST PART_NUMBER CS24702JB10
J 0
(2565 2525);
DISPLAY 0.638298 (2565 2525);
DISPLAY INVISIBLE (2565 2525);
FORCEPROP 1 LAST PATH I121
J 0
(2575 2875);
DISPLAY 0.978723 (2575 2875);
PAINT WHITE (2575 2875);
DISPLAY INVISIBLE (2575 2875);
FORCEPROP 2 LAST CDS_LIB pure_quanta
J 0
(2525 2700);
DISPLAY INVISIBLE (2525 2700);
FORCEADD UNIVERSAL_GND..1
(2525 2475);
FORCEPROP 3 LASTPIN (2525 2525) SIG_NAME GND\g
J 0
(2535 2535);
DISPLAY 0.659574 (2535 2535);
PAINT MONO (2535 2535);
DISPLAY INVISIBLE (2535 2535);
FORCEPROP 1 LAST PATH I122
J 0
(2600 2475);
DISPLAY 0.872340 (2600 2475);
PAINT AQUA (2600 2475);
DISPLAY INVISIBLE (2600 2475);
FORCEPROP 1 LAST HDL_POWER GND
J 1
(2550 2400);
DISPLAY 0.872340 (2550 2400);
PAINT GREEN (2550 2400);
DISPLAY INVISIBLE (2550 2400);
FORCEPROP 2 LAST CDS_LIB pure_quanta_power
J 0
(2525 2475);
DISPLAY INVISIBLE (2525 2475);
FORCEADD UNIVERSAL_GND..1
(2625 1350);
FORCEPROP 3 LASTPIN (2625 1400) SIG_NAME GND\g
J 0
(2635 1410);
DISPLAY 0.659574 (2635 1410);
PAINT MONO (2635 1410);
DISPLAY INVISIBLE (2635 1410);
FORCEPROP 1 LAST PATH I125
J 0
(2700 1350);
DISPLAY 0.872340 (2700 1350);
PAINT AQUA (2700 1350);
DISPLAY INVISIBLE (2700 1350);
FORCEPROP 1 LAST HDL_POWER GND
J 1
(2650 1275);
DISPLAY 0.872340 (2650 1275);
PAINT GREEN (2650 1275);
DISPLAY INVISIBLE (2650 1275);
FORCEPROP 2 LAST CDS_LIB pure_quanta_power
J 0
(2625 1350);
DISPLAY INVISIBLE (2625 1350);
FORCEADD 74LVC2G17GW..1
(1475 50);
FORCEPROP 1 LAST LOCATION U196
J 0
(1702 -190);
DISPLAY 0.723404 (1702 -190);
PAINT GREEN (1702 -190);
FORCEPROP 0 LAST $SEC 1
J 0
(1725 -150);
DISPLAY 0.680851 (1725 -150);
PAINT MONO (1725 -150);
DISPLAY INVISIBLE (1725 -150);
FORCEPROP 0 LAST CDS_SEC 1
J 0
(1725 -150);
DISPLAY 1.021277 (1725 -150);
DISPLAY INVISIBLE (1725 -150);
FORCEPROP 0 LASTPIN (1100 175) $PN 1
J 2
(1090 185);
DISPLAY 0.680851 (1090 185);
PAINT MONO (1090 185);
FORCEPROP 0 LASTPIN (1100 -75) $PN 3
J 2
(1090 -65);
DISPLAY 0.680851 (1090 -65);
PAINT MONO (1090 -65);
FORCEPROP 0 LASTPIN (1850 175) $PN 6
J 0
(1860 185);
DISPLAY 0.680851 (1860 185);
PAINT MONO (1860 185);
FORCEPROP 0 LASTPIN (1850 -75) $PN 4
J 0
(1860 -65);
DISPLAY 0.680851 (1860 -65);
PAINT MONO (1860 -65);
FORCEPROP 0 LASTPIN (1500 -375) $PN 2
R 1
J 2
(1490 -385);
DISPLAY 0.680851 (1490 -385);
PAINT MONO (1490 -385);
FORCEPROP 0 LASTPIN (1500 475) $PN 5
R 1
J 0
(1490 485);
DISPLAY 0.680851 (1490 485);
PAINT MONO (1490 485);
FORCEPROP 2 LAST VALUE 74LVC2G17GW
J 0
(1298 -680);
DISPLAY 1.021277 (1298 -680);
FORCEPROP 1 LAST MATERIAL IC
J 0
(1300 -775);
DISPLAY 0.723404 (1300 -775);
PAINT GREEN (1300 -775);
FORCEPROP 2 LAST PART_TYPE SMLF
J 0
(1298 -630);
DISPLAY 1.021277 (1298 -630);
FORCEPROP 1 LAST PART_NUMBER AL2G0017005
J 0
(1300 -725);
DISPLAY 0.723404 (1300 -725);
PAINT GREEN (1300 -725);
DISPLAY INVISIBLE (1300 -725);
FORCEPROP 1 LAST PATH I127
J 0
(1700 -225);
DISPLAY 0.723404 (1700 -225);
PAINT GREEN (1700 -225);
DISPLAY INVISIBLE (1700 -225);
FORCEPROP 2 LAST CDS_LIB pure_quanta
J 0
(1475 50);
DISPLAY INVISIBLE (1475 50);
FORCEPROP 1 LAST NEEDS_NO_SIZE TRUE
J 0
(1700 49);
DISPLAY 0.468085 (1700 49);
PAINT GREEN (1700 49);
DISPLAY INVISIBLE (1700 49);
FORCEPROP 1 LAST CDS_LMAN_SYM_OUTLINE -225,275,225,-275
J 0
(1475 50);
DISPLAY 0.468085 (1475 50);
PAINT GREEN (1475 50);
DISPLAY INVISIBLE (1475 50);
FORCEADD OFFPAGE..2
(3925 600);
FORCEPROP 2 LAST $XR0 121 
J 0
(4114 600);
DISPLAY 0.638298 (4114 600);
PAINT MONO (4114 600);
FORCEPROP 2 LAST PATH I129
J 0
(4125 650);
DISPLAY 1.021277 (4125 650);
DISPLAY INVISIBLE (4125 650);
FORCEPROP 1 LAST COMMENT_BODY TRUE
J 0
(3880 505);
DISPLAY 0.872340 (3880 505);
PAINT GREEN (3880 505);
DISPLAY INVISIBLE (3880 505);
FORCEPROP 1 LAST OFFPAGE TRUE
J 0
(4250 475);
DISPLAY 0.872340 (4250 475);
PAINT AQUA (4250 475);
DISPLAY INVISIBLE (4250 475);
FORCEPROP 2 LAST CDS_LIB standard
J 0
(3925 600);
DISPLAY INVISIBLE (3925 600);
FORCEADD UNIVERSAL_GND..1
(2625 100);
FORCEPROP 3 LASTPIN (2625 150) SIG_NAME GND\g
J 0
(2635 160);
DISPLAY 0.659574 (2635 160);
PAINT MONO (2635 160);
DISPLAY INVISIBLE (2635 160);
FORCEPROP 1 LAST PATH I132
J 0
(2700 100);
DISPLAY 0.872340 (2700 100);
PAINT AQUA (2700 100);
DISPLAY INVISIBLE (2700 100);
FORCEPROP 1 LAST HDL_POWER GND
J 1
(2650 25);
DISPLAY 0.872340 (2650 25);
PAINT GREEN (2650 25);
DISPLAY INVISIBLE (2650 25);
FORCEPROP 2 LAST CDS_LIB pure_quanta_power
J 0
(2625 100);
DISPLAY INVISIBLE (2625 100);
FORCEADD UNIVERSAL_POWER..1
(1625 1300);
FORCEPROP 3 LASTPIN (1625 1250) SIG_NAME P3V3_AUX\g
J 0
(1635 1260);
DISPLAY 0.659574 (1635 1260);
PAINT MONO (1635 1260);
DISPLAY INVISIBLE (1635 1260);
FORCEPROP 1 LAST HDL_POWER P3V3_AUX
J 1
(1625 1350);
DISPLAY 0.872340 (1625 1350);
PAINT GREEN (1625 1350);
FORCEPROP 1 LAST PATH I139
J 0
(1675 1325);
DISPLAY 0.872340 (1675 1325);
PAINT AQUA (1675 1325);
DISPLAY INVISIBLE (1675 1325);
FORCEPROP 2 LAST CDS_LIB pure_quanta_power
J 0
(1625 1300);
PAINT MONO (1625 1300);
DISPLAY INVISIBLE (1625 1300);
FORCEADD Q_CAP..1
(1625 975);
FORCEPROP 1 LAST LOCATION C1770
J 0
(1675 1075);
DISPLAY 0.787234 (1675 1075);
FORCEPROP 2 LAST $SEC 1
J 0
(1675 1175);
DISPLAY 0.680851 (1675 1175);
PAINT MONO (1675 1175);
DISPLAY INVISIBLE (1675 1175);
FORCEPROP 2 LAST CDS_SEC 1
J 0
(1675 1175);
DISPLAY 1.021277 (1675 1175);
DISPLAY INVISIBLE (1675 1175);
FORCEPROP 1 LASTPIN (1625 1075) $PN 1
J 0
(1635 1055);
DISPLAY 0.787234 (1635 1055);
FORCEPROP 1 LASTPIN (1625 875) $PN 2
J 0
(1635 855);
DISPLAY 0.787234 (1635 855);
FORCEPROP 1 LAST VALUE 0.1UF
J 0
(1675 1025);
DISPLAY 0.510638 (1675 1025);
FORCEPROP 1 LAST MATERIAL X7R
J 0
(1675 875);
DISPLAY 0.510638 (1675 875);
FORCEPROP 1 LAST TOLERANCE 10%
J 0
(1675 925);
DISPLAY 0.510638 (1675 925);
FORCEPROP 1 LAST VOLTAGE 25V
J 0
(1675 975);
DISPLAY 0.510638 (1675 975);
FORCEPROP 1 LAST PACK_TYPE 0402
J 0
(1675 775);
DISPLAY 0.510638 (1675 775);
FORCEPROP 1 LAST PART_NUMBER CH4104K1B00
J 0
(1675 825);
DISPLAY 0.510638 (1675 825);
DISPLAY INVISIBLE (1675 825);
FORCEPROP 1 LAST PATH I140
J 0
(1675 1125);
DISPLAY 0.978723 (1675 1125);
PAINT WHITE (1675 1125);
DISPLAY INVISIBLE (1675 1125);
FORCEPROP 2 LAST CDS_LIB pure_quanta
J 2
(1625 975);
PAINT MONO (1625 975);
DISPLAY INVISIBLE (1625 975);
FORCEADD UNIVERSAL_GND..1
(1625 750);
FORCEPROP 3 LASTPIN (1625 800) SIG_NAME GND\g
J 0
(1635 810);
DISPLAY 0.659574 (1635 810);
PAINT MONO (1635 810);
DISPLAY INVISIBLE (1635 810);
FORCEPROP 1 LAST PATH I141
J 0
(1700 750);
DISPLAY 0.872340 (1700 750);
PAINT AQUA (1700 750);
DISPLAY INVISIBLE (1700 750);
FORCEPROP 1 LAST HDL_POWER GND
J 1
(1650 675);
DISPLAY 0.872340 (1650 675);
PAINT GREEN (1650 675);
DISPLAY INVISIBLE (1650 675);
FORCEPROP 2 LAST CDS_LIB pure_quanta_power
J 0
(1625 750);
PAINT MONO (1625 750);
DISPLAY INVISIBLE (1625 750);
FORCEADD UNIVERSAL_GND..1
(1500 -550);
FORCEPROP 3 LASTPIN (1500 -500) SIG_NAME GND\g
J 0
(1510 -490);
DISPLAY 0.659574 (1510 -490);
PAINT MONO (1510 -490);
DISPLAY INVISIBLE (1510 -490);
FORCEPROP 1 LAST PATH I142
J 0
(1575 -550);
DISPLAY 0.872340 (1575 -550);
PAINT AQUA (1575 -550);
DISPLAY INVISIBLE (1575 -550);
FORCEPROP 1 LAST HDL_POWER GND
J 1
(1525 -625);
DISPLAY 0.872340 (1525 -625);
PAINT GREEN (1525 -625);
DISPLAY INVISIBLE (1525 -625);
FORCEPROP 2 LAST CDS_LIB pure_quanta_power
J 0
(1500 -550);
DISPLAY INVISIBLE (1500 -550);
FORCEADD OFFPAGE..4
R 2
(-250 600);
FORCEPROP 2 LAST $XR0 81 
J 0
(-471 600);
DISPLAY 0.638298 (-471 600);
PAINT MONO (-471 600);
FORCEPROP 2 LAST PATH I146
J 0
(-500 650);
DISPLAY 1.021277 (-500 650);
DISPLAY INVISIBLE (-500 650);
FORCEPROP 1 LAST COMMENT_BODY TRUE
J 2
(-225 500);
DISPLAY 0.872340 (-225 500);
PAINT GREEN (-225 500);
DISPLAY INVISIBLE (-225 500);
FORCEPROP 1 LAST OFFPAGE TRUE
J 2
(-575 475);
DISPLAY 0.872340 (-575 475);
PAINT GREEN (-575 475);
DISPLAY INVISIBLE (-575 475);
FORCEPROP 2 LAST CDS_LIB standard
J 0
(-250 600);
DISPLAY INVISIBLE (-250 600);
FORCEADD Q_RES..2
(2575 850);
FORCEPROP 1 LAST LOCATION R2912
J 0
(2620 975);
DISPLAY 0.638298 (2620 975);
FORCEPROP 2 LAST $SEC 1
J 0
(2625 1075);
DISPLAY 0.680851 (2625 1075);
PAINT MONO (2625 1075);
DISPLAY INVISIBLE (2625 1075);
FORCEPROP 2 LAST CDS_SEC 1
J 0
(2625 1075);
DISPLAY 1.021277 (2625 1075);
DISPLAY INVISIBLE (2625 1075);
FORCEPROP 1 LASTPIN (2575 950) $PN 1
J 0
(2580 912);
DISPLAY 0.787234 (2580 912);
FORCEPROP 1 LASTPIN (2575 750) $PN 2
J 0
(2580 760);
DISPLAY 0.787234 (2580 760);
FORCEPROP 1 LAST PACK_TYPE 0402LF
J 0
(2615 725);
DISPLAY 0.638298 (2615 725);
FORCEPROP 1 LAST MATERIAL EMPTY
J 0
(2615 775);
DISPLAY 0.638298 (2615 775);
PAINT RED (2615 775);
FORCEPROP 1 LAST WATTAGE 1/16W
J 0
(2615 825);
DISPLAY 0.638298 (2615 825);
FORCEPROP 1 LAST VALUE 4.7K
J 0
(2620 925);
DISPLAY 0.638298 (2620 925);
FORCEPROP 1 LAST TOLERANCE 5%
J 0
(2620 875);
DISPLAY 0.638298 (2620 875);
FORCEPROP 1 LAST PART_NUMBER CS24702JB10
J 0
(2615 675);
DISPLAY 0.638298 (2615 675);
DISPLAY INVISIBLE (2615 675);
FORCEPROP 1 LAST PATH I147
J 0
(2625 1025);
DISPLAY 0.978723 (2625 1025);
PAINT WHITE (2625 1025);
DISPLAY INVISIBLE (2625 1025);
FORCEPROP 2 LAST CDS_LIB pure_quanta
J 0
(2575 850);
PAINT MONO (2575 850);
DISPLAY INVISIBLE (2575 850);
FORCEADD UNIVERSAL_POWER..1
(2575 1100);
FORCEPROP 3 LASTPIN (2575 1050) SIG_NAME P3V3_AUX\g
J 0
(2585 1060);
DISPLAY 0.659574 (2585 1060);
PAINT MONO (2585 1060);
DISPLAY INVISIBLE (2585 1060);
FORCEPROP 1 LAST HDL_POWER P3V3_AUX
J 1
(2575 1150);
DISPLAY 0.872340 (2575 1150);
PAINT GREEN (2575 1150);
FORCEPROP 1 LAST PATH I148
J 0
(2625 1125);
DISPLAY 0.872340 (2625 1125);
PAINT AQUA (2625 1125);
DISPLAY INVISIBLE (2625 1125);
FORCEPROP 2 LAST CDS_LIB pure_quanta_power
J 0
(2575 1100);
PAINT MONO (2575 1100);
DISPLAY INVISIBLE (2575 1100);
FORCEADD Q_RES..2
(2600 2050);
FORCEPROP 1 LAST LOCATION R2911
J 0
(2645 2175);
DISPLAY 0.638298 (2645 2175);
FORCEPROP 2 LAST $SEC 1
J 0
(2650 2275);
DISPLAY 0.680851 (2650 2275);
PAINT MONO (2650 2275);
DISPLAY INVISIBLE (2650 2275);
FORCEPROP 2 LAST CDS_SEC 1
J 0
(2650 2275);
DISPLAY 1.021277 (2650 2275);
DISPLAY INVISIBLE (2650 2275);
FORCEPROP 1 LASTPIN (2600 2150) $PN 1
J 0
(2605 2112);
DISPLAY 0.787234 (2605 2112);
FORCEPROP 1 LASTPIN (2600 1950) $PN 2
J 0
(2605 1960);
DISPLAY 0.787234 (2605 1960);
FORCEPROP 1 LAST WATTAGE 1/16W
J 0
(2640 2025);
DISPLAY 0.638298 (2640 2025);
FORCEPROP 1 LAST PACK_TYPE 0402LF
J 0
(2640 1925);
DISPLAY 0.638298 (2640 1925);
FORCEPROP 1 LAST MATERIAL EMPTY
J 0
(2640 1975);
DISPLAY 0.638298 (2640 1975);
PAINT RED (2640 1975);
FORCEPROP 1 LAST TOLERANCE 5%
J 0
(2645 2075);
DISPLAY 0.638298 (2645 2075);
FORCEPROP 1 LAST VALUE 4.7K
J 0
(2645 2125);
DISPLAY 0.638298 (2645 2125);
FORCEPROP 1 LAST PART_NUMBER CS24702JB10
J 0
(2640 1875);
DISPLAY 0.638298 (2640 1875);
DISPLAY INVISIBLE (2640 1875);
FORCEPROP 1 LAST PATH I153
J 0
(2650 2225);
DISPLAY 0.978723 (2650 2225);
PAINT WHITE (2650 2225);
DISPLAY INVISIBLE (2650 2225);
FORCEPROP 2 LAST CDS_LIB pure_quanta
J 0
(2600 2050);
PAINT MONO (2600 2050);
DISPLAY INVISIBLE (2600 2050);
FORCEADD Q_RES..1
(2850 3000);
FORCEPROP 1 LAST LOCATION R2917
J 0
(2600 3000);
DISPLAY 0.723404 (2600 3000);
FORCEPROP 2 LAST $SEC 1
J 0
(2800 3200);
DISPLAY 0.680851 (2800 3200);
PAINT MONO (2800 3200);
DISPLAY INVISIBLE (2800 3200);
FORCEPROP 0 LAST CDS_SEC 1
J 0
(2550 3075);
DISPLAY INVISIBLE (2550 3075);
FORCEPROP 1 LASTPIN (2750 3000) $PN 1
J 0
(2762 3012);
DISPLAY 0.723404 (2762 3012);
PAINT MONO (2762 3012);
FORCEPROP 1 LASTPIN (2950 3000) $PN 2
J 0
(2912 3012);
DISPLAY 0.723404 (2912 3012);
PAINT MONO (2912 3012);
FORCEPROP 1 LAST PACK_TYPE 0402LF
J 0
(2675 2950);
DISPLAY 0.723404 (2675 2950);
FORCEPROP 1 LAST MATERIAL CHIP
J 0
(2875 2950);
DISPLAY 0.723404 (2875 2950);
FORCEPROP 1 LAST VALUE 49.9
J 2
(3100 3000);
DISPLAY 0.723404 (3100 3000);
FORCEPROP 1 LAST PART_NUMBER CS04992FB07
J 0
(2450 2900);
DISPLAY 0.723404 (2450 2900);
PAINT WHITE (2450 2900);
DISPLAY INVISIBLE (2450 2900);
FORCEPROP 1 LAST PATH I154
J 0
(2800 3150);
DISPLAY 0.978723 (2800 3150);
PAINT WHITE (2800 3150);
DISPLAY INVISIBLE (2800 3150);
FORCEPROP 1 LAST WATTAGE 1/16W
J 2
(3250 2950);
DISPLAY 0.723404 (3250 2950);
PAINT SKYBLUE (3250 2950);
DISPLAY INVISIBLE (3250 2950);
FORCEPROP 1 LAST TOLERANCE 1%
J 0
(3325 3000);
DISPLAY 0.723404 (3325 3000);
PAINT SKYBLUE (3325 3000);
DISPLAY INVISIBLE (3325 3000);
FORCEPROP 2 LAST CDS_LIB pure_quanta
J 0
(2850 3000);
DISPLAY INVISIBLE (2850 3000);
FORCEADD Q_RES..1
(2925 1875);
FORCEPROP 1 LAST LOCATION R2924
J 0
(2700 1875);
DISPLAY 0.638298 (2700 1875);
FORCEPROP 0 LAST $SEC 1
J 0
(2875 1975);
DISPLAY 0.680851 (2875 1975);
PAINT MONO (2875 1975);
DISPLAY INVISIBLE (2875 1975);
FORCEPROP 0 LAST CDS_SEC 1
J 0
(2875 1975);
DISPLAY 1.021277 (2875 1975);
DISPLAY INVISIBLE (2875 1975);
FORCEPROP 1 LASTPIN (2825 1875) $PN 1
J 0
(2837 1887);
DISPLAY 0.787234 (2837 1887);
PAINT MONO (2837 1887);
FORCEPROP 1 LASTPIN (3025 1875) $PN 2
J 0
(2987 1887);
DISPLAY 0.787234 (2987 1887);
PAINT MONO (2987 1887);
FORCEPROP 1 LAST VALUE 49.9
J 2
(3175 1875);
DISPLAY 0.723404 (3175 1875);
FORCEPROP 1 LAST PACK_TYPE 0402LF
J 0
(2750 1825);
DISPLAY 0.723404 (2750 1825);
FORCEPROP 1 LAST MATERIAL CHIP
J 0
(2950 1825);
DISPLAY 0.723404 (2950 1825);
FORCEPROP 1 LAST PART_NUMBER CS04992FB07
J 0
(2525 1775);
DISPLAY 0.723404 (2525 1775);
PAINT WHITE (2525 1775);
DISPLAY INVISIBLE (2525 1775);
FORCEPROP 1 LAST PATH I155
J 0
(2875 2025);
DISPLAY 0.978723 (2875 2025);
PAINT WHITE (2875 2025);
DISPLAY INVISIBLE (2875 2025);
FORCEPROP 1 LAST WATTAGE 1/16W
J 2
(3325 1825);
DISPLAY 0.723404 (3325 1825);
PAINT SKYBLUE (3325 1825);
DISPLAY INVISIBLE (3325 1825);
FORCEPROP 1 LAST TOLERANCE 1%
J 0
(3400 1875);
DISPLAY 0.723404 (3400 1875);
PAINT SKYBLUE (3400 1875);
DISPLAY INVISIBLE (3400 1875);
FORCEPROP 2 LAST CDS_LIB pure_quanta
J 0
(2925 1875);
DISPLAY INVISIBLE (2925 1875);
FORCEADD Q_RES..1
(2825 600);
FORCEPROP 1 LAST LOCATION R2925
J 0
(2600 600);
DISPLAY 0.787234 (2600 600);
FORCEPROP 0 LAST $SEC 1
J 0
(2775 700);
DISPLAY 0.680851 (2775 700);
PAINT MONO (2775 700);
DISPLAY INVISIBLE (2775 700);
FORCEPROP 0 LAST CDS_SEC 1
J 0
(2775 700);
DISPLAY 1.021277 (2775 700);
DISPLAY INVISIBLE (2775 700);
FORCEPROP 1 LASTPIN (2725 600) $PN 1
J 0
(2737 612);
DISPLAY 0.787234 (2737 612);
PAINT MONO (2737 612);
FORCEPROP 1 LASTPIN (2925 600) $PN 2
J 0
(2887 612);
DISPLAY 0.787234 (2887 612);
PAINT MONO (2887 612);
FORCEPROP 1 LAST VALUE 49.9
J 2
(3100 600);
DISPLAY 0.723404 (3100 600);
FORCEPROP 1 LAST MATERIAL CHIP
J 0
(2850 550);
DISPLAY 0.723404 (2850 550);
FORCEPROP 1 LAST PACK_TYPE 0402LF
J 0
(2650 550);
DISPLAY 0.723404 (2650 550);
FORCEPROP 1 LAST PART_NUMBER CS04992FB07
J 0
(2425 500);
DISPLAY 0.723404 (2425 500);
PAINT WHITE (2425 500);
DISPLAY INVISIBLE (2425 500);
FORCEPROP 1 LAST PATH I156
J 0
(2775 750);
DISPLAY 0.978723 (2775 750);
PAINT WHITE (2775 750);
DISPLAY INVISIBLE (2775 750);
FORCEPROP 1 LAST TOLERANCE 1%
J 0
(3300 600);
DISPLAY 0.723404 (3300 600);
PAINT SKYBLUE (3300 600);
DISPLAY INVISIBLE (3300 600);
FORCEPROP 1 LAST WATTAGE 1/16W
J 2
(3225 550);
DISPLAY 0.723404 (3225 550);
PAINT SKYBLUE (3225 550);
DISPLAY INVISIBLE (3225 550);
FORCEPROP 2 LAST CDS_LIB pure_quanta
J 0
(2825 600);
DISPLAY INVISIBLE (2825 600);
FORCEADD UNIVERSAL_GND..1
(-50 225);
FORCEPROP 3 LASTPIN (-50 275) SIG_NAME GND\g
J 0
(-40 285);
DISPLAY 0.659574 (-40 285);
PAINT MONO (-40 285);
DISPLAY INVISIBLE (-40 285);
FORCEPROP 1 LAST PATH I159
J 0
(25 225);
DISPLAY 0.872340 (25 225);
PAINT AQUA (25 225);
DISPLAY INVISIBLE (25 225);
FORCEPROP 1 LAST HDL_POWER GND
J 1
(-25 150);
DISPLAY 0.872340 (-25 150);
PAINT GREEN (-25 150);
DISPLAY INVISIBLE (-25 150);
FORCEPROP 2 LAST CDS_LIB pure_quanta_power
J 0
(-50 225);
DISPLAY INVISIBLE (-50 225);
FORCEADD Q_RES..2
(-50 400);
FORCEPROP 1 LAST LOCATION R2937
J 0
(-5 525);
DISPLAY 0.638298 (-5 525);
FORCEPROP 2 LAST $SEC 1
J 0
(0 625);
DISPLAY 0.680851 (0 625);
PAINT MONO (0 625);
DISPLAY INVISIBLE (0 625);
FORCEPROP 2 LAST CDS_SEC 1
J 0
(0 625);
DISPLAY 1.021277 (0 625);
DISPLAY INVISIBLE (0 625);
FORCEPROP 1 LASTPIN (-50 500) $PN 1
J 0
(-45 462);
DISPLAY 0.787234 (-45 462);
FORCEPROP 1 LASTPIN (-50 300) $PN 2
J 0
(-45 310);
DISPLAY 0.787234 (-45 310);
FORCEPROP 1 LAST WATTAGE 1/16W
J 0
(-10 375);
DISPLAY 0.638298 (-10 375);
FORCEPROP 1 LAST VALUE 4.7K
J 0
(-5 475);
DISPLAY 0.638298 (-5 475);
FORCEPROP 1 LAST PACK_TYPE 0402LF
J 0
(-10 275);
DISPLAY 0.638298 (-10 275);
FORCEPROP 1 LAST MATERIAL CHIP
J 0
(-10 325);
DISPLAY 0.638298 (-10 325);
FORCEPROP 1 LAST TOLERANCE 5%
J 0
(-5 425);
DISPLAY 0.638298 (-5 425);
FORCEPROP 1 LAST PART_NUMBER CS24702JB10
J 0
(-10 225);
DISPLAY 0.638298 (-10 225);
DISPLAY INVISIBLE (-10 225);
FORCEPROP 1 LAST PATH I160
J 0
(0 575);
DISPLAY 0.978723 (0 575);
PAINT WHITE (0 575);
DISPLAY INVISIBLE (0 575);
FORCEPROP 2 LAST CDS_LIB pure_quanta
J 0
(-50 400);
PAINT MONO (-50 400);
DISPLAY INVISIBLE (-50 400);
FORCEADD UNIVERSAL_POWER..1
(-75 1125);
FORCEPROP 3 LASTPIN (-75 1075) SIG_NAME P3V3_AUX\g
J 0
(-65 1085);
DISPLAY 0.659574 (-65 1085);
PAINT MONO (-65 1085);
DISPLAY INVISIBLE (-65 1085);
FORCEPROP 1 LAST HDL_POWER P3V3_AUX
J 1
(-75 1175);
DISPLAY 0.872340 (-75 1175);
PAINT GREEN (-75 1175);
FORCEPROP 1 LAST PATH I161
J 0
(-25 1150);
DISPLAY 0.872340 (-25 1150);
PAINT AQUA (-25 1150);
DISPLAY INVISIBLE (-25 1150);
FORCEPROP 2 LAST CDS_LIB pure_quanta_power
J 0
(-75 1125);
PAINT MONO (-75 1125);
DISPLAY INVISIBLE (-75 1125);
FORCEADD Q_RES..2
(-75 875);
FORCEPROP 1 LAST LOCATION R2936
J 0
(-30 1000);
DISPLAY 0.978723 (-30 1000);
FORCEPROP 0 LAST $SEC 1
J 0
(-25 1050);
DISPLAY 0.680851 (-25 1050);
PAINT MONO (-25 1050);
DISPLAY INVISIBLE (-25 1050);
FORCEPROP 0 LAST CDS_SEC 1
J 0
(-25 1050);
DISPLAY 1.021277 (-25 1050);
DISPLAY INVISIBLE (-25 1050);
FORCEPROP 1 LASTPIN (-75 975) $PN 1
J 0
(-70 937);
DISPLAY 0.787234 (-70 937);
PAINT MONO (-70 937);
FORCEPROP 1 LASTPIN (-75 775) $PN 2
J 0
(-70 785);
DISPLAY 0.787234 (-70 785);
PAINT MONO (-70 785);
FORCEPROP 1 LAST WATTAGE 1/16W
J 0
(-35 850);
DISPLAY 0.510638 (-35 850);
FORCEPROP 1 LAST MATERIAL EMPTY
J 0
(-35 800);
DISPLAY 0.510638 (-35 800);
PAINT RED (-35 800);
FORCEPROP 1 LAST VALUE 100K
J 0
(-30 950);
DISPLAY 0.510638 (-30 950);
FORCEPROP 1 LAST TOLERANCE 1%
J 0
(-30 900);
DISPLAY 0.510638 (-30 900);
FORCEPROP 1 LAST PACK_TYPE 0402LF
J 0
(-35 700);
DISPLAY 0.510638 (-35 700);
FORCEPROP 1 LAST PART_NUMBER CS41002FB09
J 0
(-35 750);
DISPLAY 0.510638 (-35 750);
DISPLAY INVISIBLE (-35 750);
FORCEPROP 1 LAST PATH I162
J 0
(-25 1050);
DISPLAY 0.978723 (-25 1050);
PAINT WHITE (-25 1050);
DISPLAY INVISIBLE (-25 1050);
FORCEPROP 2 LAST CDS_LIB pure_quanta
J 0
(-75 875);
DISPLAY INVISIBLE (-75 875);
FORCEADD OFFPAGE..2
(4200 -1950);
FORCEPROP 2 LAST $XR0 150 
J 0
(4389 -1950);
DISPLAY 0.638298 (4389 -1950);
PAINT MONO (4389 -1950);
FORCEPROP 2 LAST PATH I163
J 0
(4400 -1900);
DISPLAY 1.021277 (4400 -1900);
DISPLAY INVISIBLE (4400 -1900);
FORCEPROP 1 LAST COMMENT_BODY TRUE
J 0
(4155 -2045);
DISPLAY 0.872340 (4155 -2045);
PAINT GREEN (4155 -2045);
DISPLAY INVISIBLE (4155 -2045);
FORCEPROP 1 LAST OFFPAGE TRUE
J 0
(4525 -2075);
DISPLAY 0.872340 (4525 -2075);
PAINT AQUA (4525 -2075);
DISPLAY INVISIBLE (4525 -2075);
FORCEPROP 2 LAST CDS_LIB standard
J 0
(4200 -1950);
DISPLAY INVISIBLE (4200 -1950);
FORCEADD UNIVERSAL_POWER..1
(2225 -1100);
FORCEPROP 3 LASTPIN (2225 -1150) SIG_NAME P3V3_AUX\g
J 0
(2235 -1140);
DISPLAY 0.659574 (2235 -1140);
PAINT MONO (2235 -1140);
DISPLAY INVISIBLE (2235 -1140);
FORCEPROP 1 LAST HDL_POWER P3V3_AUX
J 1
(2225 -1050);
DISPLAY 0.872340 (2225 -1050);
PAINT GREEN (2225 -1050);
FORCEPROP 1 LAST PATH I165
J 0
(2275 -1075);
DISPLAY 0.872340 (2275 -1075);
PAINT AQUA (2275 -1075);
DISPLAY INVISIBLE (2275 -1075);
FORCEPROP 2 LAST CDS_LIB pure_quanta_power
J 0
(2225 -1100);
PAINT MONO (2225 -1100);
DISPLAY INVISIBLE (2225 -1100);
FORCEADD Q_CAP..1
(2225 -1425);
FORCEPROP 1 LAST LOCATION C1803
J 0
(2275 -1325);
DISPLAY 0.787234 (2275 -1325);
FORCEPROP 2 LAST $SEC 1
J 0
(2275 -1225);
DISPLAY 0.680851 (2275 -1225);
PAINT MONO (2275 -1225);
DISPLAY INVISIBLE (2275 -1225);
FORCEPROP 2 LAST CDS_SEC 1
J 0
(2275 -1225);
DISPLAY 1.021277 (2275 -1225);
DISPLAY INVISIBLE (2275 -1225);
FORCEPROP 1 LASTPIN (2225 -1325) $PN 1
J 0
(2235 -1345);
DISPLAY 0.787234 (2235 -1345);
FORCEPROP 1 LASTPIN (2225 -1525) $PN 2
J 0
(2235 -1545);
DISPLAY 0.787234 (2235 -1545);
FORCEPROP 1 LAST MATERIAL X7R
J 0
(2275 -1525);
DISPLAY 0.510638 (2275 -1525);
FORCEPROP 1 LAST VALUE 0.1UF
J 0
(2275 -1375);
DISPLAY 0.510638 (2275 -1375);
FORCEPROP 1 LAST VOLTAGE 25V
J 0
(2275 -1425);
DISPLAY 0.510638 (2275 -1425);
FORCEPROP 1 LAST TOLERANCE 10%
J 0
(2275 -1475);
DISPLAY 0.510638 (2275 -1475);
FORCEPROP 1 LAST PACK_TYPE 0402
J 0
(2275 -1625);
DISPLAY 0.510638 (2275 -1625);
FORCEPROP 1 LAST PART_NUMBER CH4104K1B00
J 0
(2275 -1575);
DISPLAY 0.510638 (2275 -1575);
DISPLAY INVISIBLE (2275 -1575);
FORCEPROP 1 LAST PATH I166
J 0
(2275 -1275);
DISPLAY 0.978723 (2275 -1275);
PAINT WHITE (2275 -1275);
DISPLAY INVISIBLE (2275 -1275);
FORCEPROP 2 LAST CDS_LIB pure_quanta
J 2
(2225 -1425);
PAINT MONO (2225 -1425);
DISPLAY INVISIBLE (2225 -1425);
FORCEADD UNIVERSAL_GND..1
(2225 -1650);
FORCEPROP 3 LASTPIN (2225 -1600) SIG_NAME GND\g
J 0
(2235 -1590);
DISPLAY 0.659574 (2235 -1590);
PAINT MONO (2235 -1590);
DISPLAY INVISIBLE (2235 -1590);
FORCEPROP 1 LAST PATH I167
J 0
(2300 -1650);
DISPLAY 0.872340 (2300 -1650);
PAINT AQUA (2300 -1650);
DISPLAY INVISIBLE (2300 -1650);
FORCEPROP 1 LAST HDL_POWER GND
J 1
(2250 -1725);
DISPLAY 0.872340 (2250 -1725);
PAINT GREEN (2250 -1725);
DISPLAY INVISIBLE (2250 -1725);
FORCEPROP 2 LAST CDS_LIB pure_quanta_power
J 0
(2225 -1650);
PAINT MONO (2225 -1650);
DISPLAY INVISIBLE (2225 -1650);
FORCEADD Q_RES..1
(975 -1900);
FORCEPROP 1 LAST LOCATION R3033
J 0
(750 -1900);
DISPLAY 0.723404 (750 -1900);
FORCEPROP 2 LAST $SEC 1
J 0
(925 -1700);
DISPLAY 0.680851 (925 -1700);
PAINT MONO (925 -1700);
DISPLAY INVISIBLE (925 -1700);
FORCEPROP 2 LAST CDS_SEC 1
J 0
(925 -1700);
DISPLAY 1.021277 (925 -1700);
DISPLAY INVISIBLE (925 -1700);
FORCEPROP 1 LASTPIN (875 -1900) $PN 1
J 0
(887 -1888);
DISPLAY 0.787234 (887 -1888);
PAINT MONO (887 -1888);
FORCEPROP 1 LASTPIN (1075 -1900) $PN 2
J 0
(1037 -1888);
DISPLAY 0.787234 (1037 -1888);
PAINT MONO (1037 -1888);
FORCEPROP 1 LAST PACK_TYPE 0402LF
J 0
(975 -1850);
DISPLAY 0.723404 (975 -1850);
FORCEPROP 1 LAST VALUE 0
J 2
(1125 -1900);
DISPLAY 0.723404 (1125 -1900);
FORCEPROP 1 LAST MATERIAL CHIP
J 0
(825 -1850);
DISPLAY 0.723404 (825 -1850);
FORCEPROP 1 LAST PART_NUMBER CS00002JB13
J 0
(700 -2025);
DISPLAY 0.723404 (700 -2025);
PAINT WHITE (700 -2025);
DISPLAY INVISIBLE (700 -2025);
FORCEPROP 1 LAST PATH I170
J 0
(925 -1750);
DISPLAY 0.978723 (925 -1750);
PAINT WHITE (925 -1750);
DISPLAY INVISIBLE (925 -1750);
FORCEPROP 1 LAST WATTAGE 1/16W
J 2
(1050 -1975);
DISPLAY 0.723404 (1050 -1975);
PAINT SKYBLUE (1050 -1975);
DISPLAY INVISIBLE (1050 -1975);
FORCEPROP 1 LAST TOLERANCE 5%
J 0
(775 -1975);
DISPLAY 0.723404 (775 -1975);
PAINT SKYBLUE (775 -1975);
DISPLAY INVISIBLE (775 -1975);
FORCEPROP 2 LAST CDS_LIB pure_quanta
J 0
(975 -1900);
DISPLAY INVISIBLE (975 -1900);
FORCEADD Q_RES..1
(975 -2000);
FORCEPROP 1 LAST LOCATION R3063
J 0
(750 -2000);
DISPLAY 0.638298 (750 -2000);
FORCEPROP 0 LAST $SEC 1
J 0
(750 -1925);
DISPLAY 0.680851 (750 -1925);
PAINT MONO (750 -1925);
DISPLAY INVISIBLE (750 -1925);
FORCEPROP 0 LAST CDS_SEC 1
J 0
(750 -1925);
DISPLAY 1.021277 (750 -1925);
DISPLAY INVISIBLE (750 -1925);
FORCEPROP 1 LASTPIN (875 -2000) $PN 1
J 0
(887 -1988);
DISPLAY 0.787234 (887 -1988);
PAINT MONO (887 -1988);
FORCEPROP 1 LASTPIN (1075 -2000) $PN 2
J 0
(1037 -1988);
DISPLAY 0.787234 (1037 -1988);
PAINT MONO (1037 -1988);
FORCEPROP 1 LAST MATERIAL CHIP
J 0
(750 -2050);
DISPLAY 0.723404 (750 -2050);
FORCEPROP 1 LAST PACK_TYPE 0402LF
J 0
(950 -2075);
DISPLAY 0.723404 (950 -2075);
FORCEPROP 1 LAST VALUE 0
J 2
(1125 -2000);
DISPLAY 0.723404 (1125 -2000);
FORCEPROP 1 LAST PART_NUMBER CS00002JB13
J 0
(700 -2125);
DISPLAY 0.723404 (700 -2125);
PAINT WHITE (700 -2125);
DISPLAY INVISIBLE (700 -2125);
FORCEPROP 1 LAST PATH I171
J 0
(925 -1850);
DISPLAY 0.978723 (925 -1850);
PAINT WHITE (925 -1850);
DISPLAY INVISIBLE (925 -1850);
FORCEPROP 1 LAST TOLERANCE 5%
J 0
(775 -2075);
DISPLAY 0.723404 (775 -2075);
PAINT SKYBLUE (775 -2075);
DISPLAY INVISIBLE (775 -2075);
FORCEPROP 1 LAST WATTAGE 1/16W
J 2
(1050 -2075);
DISPLAY 0.723404 (1050 -2075);
PAINT SKYBLUE (1050 -2075);
DISPLAY INVISIBLE (1050 -2075);
FORCEPROP 2 LAST CDS_LIB pure_quanta
J 0
(975 -2000);
DISPLAY INVISIBLE (975 -2000);
FORCEADD OFFPAGE..4
R 2
(-50 -2000);
FORCEPROP 2 LAST $XR0 241 
J 0
(-302 -2000);
DISPLAY 0.638298 (-302 -2000);
PAINT MONO (-302 -2000);
FORCEPROP 2 LAST PATH I172
J 0
(-325 -1950);
DISPLAY 1.021277 (-325 -1950);
DISPLAY INVISIBLE (-325 -1950);
FORCEPROP 1 LAST COMMENT_BODY TRUE
J 2
(-25 -2100);
DISPLAY 0.872340 (-25 -2100);
PAINT GREEN (-25 -2100);
DISPLAY INVISIBLE (-25 -2100);
FORCEPROP 1 LAST OFFPAGE TRUE
J 2
(-375 -2125);
DISPLAY 0.872340 (-375 -2125);
PAINT GREEN (-375 -2125);
DISPLAY INVISIBLE (-375 -2125);
FORCEPROP 2 LAST CDS_LIB standard
J 0
(-50 -2000);
DISPLAY INVISIBLE (-50 -2000);
FORCEADD OFFPAGE..4
R 2
(-50 -1900);
FORCEPROP 2 LAST $XR0 116 
J 0
(-302 -1900);
DISPLAY 0.638298 (-302 -1900);
PAINT MONO (-302 -1900);
FORCEPROP 2 LAST PATH I173
J 0
(-325 -1850);
DISPLAY 1.021277 (-325 -1850);
DISPLAY INVISIBLE (-325 -1850);
FORCEPROP 1 LAST COMMENT_BODY TRUE
J 2
(-25 -2000);
DISPLAY 0.872340 (-25 -2000);
PAINT GREEN (-25 -2000);
DISPLAY INVISIBLE (-25 -2000);
FORCEPROP 1 LAST OFFPAGE TRUE
J 2
(-375 -2025);
DISPLAY 0.872340 (-375 -2025);
PAINT GREEN (-375 -2025);
DISPLAY INVISIBLE (-375 -2025);
FORCEPROP 2 LAST CDS_LIB standard
J 0
(-50 -1900);
DISPLAY INVISIBLE (-50 -1900);
FORCEADD UNIVERSAL_POWER..1
(0 0);
FORCEPROP 3 LASTPIN (0 -50) SIG_NAME P3V3_AUX\g
J 0
(10 -40);
DISPLAY 0.659574 (10 -40);
PAINT MONO (10 -40);
DISPLAY INVISIBLE (10 -40);
FORCEPROP 1 LAST HDL_POWER P3V3_AUX
J 1
(0 50);
DISPLAY 0.872340 (0 50);
PAINT GREEN (0 50);
FORCEPROP 1 LAST PATH I174
J 0
(50 25);
DISPLAY 0.872340 (50 25);
PAINT AQUA (50 25);
DISPLAY INVISIBLE (50 25);
FORCEPROP 2 LAST CDS_LIB pure_quanta_power
J 0
(0 0);
PAINT MONO (0 0);
DISPLAY INVISIBLE (0 0);
FORCEADD OFFPAGE..4
R 2
(-200 -525);
FORCEPROP 2 LAST $XR0 81 
J 0
(-451 -525);
DISPLAY 0.638298 (-451 -525);
PAINT MONO (-451 -525);
FORCEPROP 2 LAST PATH I177
J 0
(-475 -475);
DISPLAY 1.021277 (-475 -475);
DISPLAY INVISIBLE (-475 -475);
FORCEPROP 1 LAST COMMENT_BODY TRUE
J 2
(-175 -625);
DISPLAY 0.872340 (-175 -625);
PAINT GREEN (-175 -625);
DISPLAY INVISIBLE (-175 -625);
FORCEPROP 1 LAST OFFPAGE TRUE
J 2
(-525 -650);
DISPLAY 0.872340 (-525 -650);
PAINT GREEN (-525 -650);
DISPLAY INVISIBLE (-525 -650);
FORCEPROP 2 LAST CDS_LIB standard
J 0
(-200 -525);
DISPLAY INVISIBLE (-200 -525);
FORCEADD UNIVERSAL_GND..1
(2650 -1025);
FORCEPROP 3 LASTPIN (2650 -975) SIG_NAME GND\g
J 0
(2660 -965);
DISPLAY 0.659574 (2660 -965);
PAINT MONO (2660 -965);
DISPLAY INVISIBLE (2660 -965);
FORCEPROP 1 LAST PATH I178
J 0
(2725 -1025);
DISPLAY 0.872340 (2725 -1025);
PAINT AQUA (2725 -1025);
DISPLAY INVISIBLE (2725 -1025);
FORCEPROP 1 LAST HDL_POWER GND
J 1
(2675 -1100);
DISPLAY 0.872340 (2675 -1100);
PAINT GREEN (2675 -1100);
DISPLAY INVISIBLE (2675 -1100);
FORCEPROP 2 LAST CDS_LIB pure_quanta_power
J 0
(2650 -1025);
DISPLAY INVISIBLE (2650 -1025);
FORCEADD OFFPAGE..2
(3975 -525);
FORCEPROP 2 LAST $XR0 121 
J 0
(4164 -525);
DISPLAY 0.638298 (4164 -525);
PAINT MONO (4164 -525);
FORCEPROP 2 LAST PATH I180
J 0
(4175 -475);
DISPLAY 1.021277 (4175 -475);
DISPLAY INVISIBLE (4175 -475);
FORCEPROP 1 LAST COMMENT_BODY TRUE
J 0
(3930 -620);
DISPLAY 0.872340 (3930 -620);
PAINT GREEN (3930 -620);
DISPLAY INVISIBLE (3930 -620);
FORCEPROP 1 LAST OFFPAGE TRUE
J 0
(4300 -650);
DISPLAY 0.872340 (4300 -650);
PAINT AQUA (4300 -650);
DISPLAY INVISIBLE (4300 -650);
FORCEPROP 2 LAST CDS_LIB standard
J 0
(3975 -525);
DISPLAY INVISIBLE (3975 -525);
FORCEADD Q_RES..1
(2900 -525);
FORCEPROP 1 LAST LOCATION R3315
J 0
(2675 -525);
DISPLAY 0.638298 (2675 -525);
FORCEPROP 0 LAST $SEC 1
J 0
(2850 -425);
DISPLAY 0.680851 (2850 -425);
PAINT MONO (2850 -425);
DISPLAY INVISIBLE (2850 -425);
FORCEPROP 0 LAST CDS_SEC 1
J 0
(2850 -425);
DISPLAY 1.021277 (2850 -425);
DISPLAY INVISIBLE (2850 -425);
FORCEPROP 1 LASTPIN (2800 -525) $PN 1
J 0
(2812 -513);
DISPLAY 0.787234 (2812 -513);
PAINT MONO (2812 -513);
FORCEPROP 1 LASTPIN (3000 -525) $PN 2
J 0
(2962 -513);
DISPLAY 0.787234 (2962 -513);
PAINT MONO (2962 -513);
FORCEPROP 1 LAST PACK_TYPE 0402LF
J 0
(2725 -575);
DISPLAY 0.723404 (2725 -575);
FORCEPROP 1 LAST VALUE 33.2
J 2
(3150 -525);
DISPLAY 0.723404 (3150 -525);
FORCEPROP 1 LAST MATERIAL CHIP
J 0
(2925 -575);
DISPLAY 0.723404 (2925 -575);
FORCEPROP 1 LAST PART_NUMBER CS03322FB03
J 0
(2500 -625);
DISPLAY 0.723404 (2500 -625);
PAINT WHITE (2500 -625);
DISPLAY INVISIBLE (2500 -625);
FORCEPROP 1 LAST PATH I181
J 0
(2850 -375);
DISPLAY 0.978723 (2850 -375);
PAINT WHITE (2850 -375);
DISPLAY INVISIBLE (2850 -375);
FORCEPROP 2 LAST CDS_LIB pure_quanta
J 0
(2900 -525);
DISPLAY INVISIBLE (2900 -525);
FORCEPROP 1 LAST WATTAGE 1/16W
J 2
(3300 -575);
DISPLAY 0.723404 (3300 -575);
PAINT SKYBLUE (3300 -575);
DISPLAY INVISIBLE (3300 -575);
FORCEPROP 1 LAST TOLERANCE 1%
J 0
(3375 -525);
DISPLAY 0.723404 (3375 -525);
PAINT SKYBLUE (3375 -525);
DISPLAY INVISIBLE (3375 -525);
FORCEADD UNIVERSAL_POWER..1
(2650 -75);
FORCEPROP 3 LASTPIN (2650 -125) SIG_NAME P3V3_AUX\g
J 0
(2660 -115);
DISPLAY 0.659574 (2660 -115);
PAINT MONO (2660 -115);
DISPLAY INVISIBLE (2660 -115);
FORCEPROP 1 LAST HDL_POWER P3V3_AUX
J 1
(2650 -25);
DISPLAY 0.872340 (2650 -25);
PAINT GREEN (2650 -25);
FORCEPROP 1 LAST PATH I183
J 0
(2700 -50);
DISPLAY 0.872340 (2700 -50);
PAINT AQUA (2700 -50);
DISPLAY INVISIBLE (2700 -50);
FORCEPROP 2 LAST CDS_LIB pure_quanta_power
J 0
(2650 -75);
PAINT MONO (2650 -75);
DISPLAY INVISIBLE (2650 -75);
FORCEADD UNIVERSAL_GND..1
(25 -900);
FORCEPROP 3 LASTPIN (25 -850) SIG_NAME GND\g
J 0
(35 -840);
DISPLAY 0.659574 (35 -840);
PAINT MONO (35 -840);
DISPLAY INVISIBLE (35 -840);
FORCEPROP 1 LAST PATH I184
J 0
(100 -900);
DISPLAY 0.872340 (100 -900);
PAINT AQUA (100 -900);
DISPLAY INVISIBLE (100 -900);
FORCEPROP 1 LAST HDL_POWER GND
J 1
(50 -975);
DISPLAY 0.872340 (50 -975);
PAINT GREEN (50 -975);
DISPLAY INVISIBLE (50 -975);
FORCEPROP 2 LAST CDS_LIB pure_quanta_power
J 0
(25 -900);
DISPLAY INVISIBLE (25 -900);
FORCEADD Q_RES..2
(2650 -325);
FORCEPROP 1 LAST LOCATION R3317
J 0
(2695 -200);
DISPLAY 0.638298 (2695 -200);
FORCEPROP 2 LAST $SEC 1
J 0
(2700 -100);
DISPLAY 0.680851 (2700 -100);
PAINT MONO (2700 -100);
DISPLAY INVISIBLE (2700 -100);
FORCEPROP 2 LAST CDS_SEC 1
J 0
(2700 -100);
DISPLAY 1.021277 (2700 -100);
DISPLAY INVISIBLE (2700 -100);
FORCEPROP 1 LASTPIN (2650 -225) $PN 1
J 0
(2655 -263);
DISPLAY 0.787234 (2655 -263);
FORCEPROP 1 LASTPIN (2650 -425) $PN 2
J 0
(2655 -415);
DISPLAY 0.787234 (2655 -415);
FORCEPROP 1 LAST TOLERANCE 5%
J 0
(2695 -300);
DISPLAY 0.638298 (2695 -300);
FORCEPROP 1 LAST VALUE 4.7K
J 0
(2695 -250);
DISPLAY 0.638298 (2695 -250);
FORCEPROP 1 LAST WATTAGE 1/16W
J 0
(2690 -350);
DISPLAY 0.638298 (2690 -350);
FORCEPROP 1 LAST MATERIAL EMPTY
J 0
(2690 -400);
DISPLAY 0.638298 (2690 -400);
PAINT RED (2690 -400);
FORCEPROP 1 LAST PACK_TYPE 0402LF
J 0
(2690 -450);
DISPLAY 0.638298 (2690 -450);
FORCEPROP 1 LAST PART_NUMBER CS24702JB10
J 0
(2690 -500);
DISPLAY 0.638298 (2690 -500);
DISPLAY INVISIBLE (2690 -500);
FORCEPROP 1 LAST PATH I190
J 0
(2700 -150);
DISPLAY 0.978723 (2700 -150);
PAINT WHITE (2700 -150);
DISPLAY INVISIBLE (2700 -150);
FORCEPROP 2 LAST CDS_LIB pure_quanta
J 0
(2650 -325);
PAINT MONO (2650 -325);
DISPLAY INVISIBLE (2650 -325);
FORCEADD Q_RES..2
(2650 -800);
FORCEPROP 1 LAST LOCATION R3509
J 0
(2695 -675);
DISPLAY 0.978723 (2695 -675);
FORCEPROP 0 LAST $SEC 1
J 0
(2700 -625);
DISPLAY 0.680851 (2700 -625);
PAINT MONO (2700 -625);
DISPLAY INVISIBLE (2700 -625);
FORCEPROP 0 LAST CDS_SEC 1
J 0
(2700 -625);
DISPLAY 1.021277 (2700 -625);
DISPLAY INVISIBLE (2700 -625);
FORCEPROP 1 LASTPIN (2650 -700) $PN 1
J 0
(2655 -738);
DISPLAY 0.787234 (2655 -738);
PAINT MONO (2655 -738);
FORCEPROP 1 LASTPIN (2650 -900) $PN 2
J 0
(2655 -890);
DISPLAY 0.787234 (2655 -890);
PAINT MONO (2655 -890);
FORCEPROP 1 LAST PACK_TYPE 0402LF
J 0
(2690 -975);
DISPLAY 0.510638 (2690 -975);
FORCEPROP 1 LAST TOLERANCE 1%
J 0
(2695 -775);
DISPLAY 0.510638 (2695 -775);
FORCEPROP 1 LAST VALUE 10K
J 0
(2695 -725);
DISPLAY 0.510638 (2695 -725);
FORCEPROP 1 LAST WATTAGE 1/16W
J 0
(2690 -825);
DISPLAY 0.510638 (2690 -825);
FORCEPROP 1 LAST MATERIAL CHIP
J 0
(2690 -875);
DISPLAY 0.510638 (2690 -875);
FORCEPROP 1 LAST PART_NUMBER CS31002FB08
J 0
(2690 -925);
DISPLAY 0.510638 (2690 -925);
DISPLAY INVISIBLE (2690 -925);
FORCEPROP 1 LAST PATH I191
J 0
(2700 -625);
DISPLAY 0.978723 (2700 -625);
PAINT WHITE (2700 -625);
DISPLAY INVISIBLE (2700 -625);
FORCEPROP 2 LAST CDS_LIB pure_quanta
J 0
(2650 -800);
DISPLAY INVISIBLE (2650 -800);
FORCEADD Q_RES..2
(25 -725);
FORCEPROP 1 LAST LOCATION R3507
J 0
(70 -600);
DISPLAY 0.978723 (70 -600);
FORCEPROP 0 LAST $SEC 1
J 0
(75 -550);
DISPLAY 0.680851 (75 -550);
PAINT MONO (75 -550);
DISPLAY INVISIBLE (75 -550);
FORCEPROP 0 LAST CDS_SEC 1
J 0
(75 -550);
DISPLAY 1.021277 (75 -550);
DISPLAY INVISIBLE (75 -550);
FORCEPROP 1 LASTPIN (25 -625) $PN 1
J 0
(30 -663);
DISPLAY 0.787234 (30 -663);
PAINT MONO (30 -663);
FORCEPROP 1 LASTPIN (25 -825) $PN 2
J 0
(30 -815);
DISPLAY 0.787234 (30 -815);
PAINT MONO (30 -815);
FORCEPROP 1 LAST WATTAGE 1/16W
J 0
(65 -750);
DISPLAY 0.510638 (65 -750);
FORCEPROP 1 LAST TOLERANCE 1%
J 0
(70 -700);
DISPLAY 0.510638 (70 -700);
FORCEPROP 1 LAST MATERIAL CHIP
J 0
(65 -800);
DISPLAY 0.510638 (65 -800);
FORCEPROP 1 LAST VALUE 10K
J 0
(70 -650);
DISPLAY 0.510638 (70 -650);
FORCEPROP 1 LAST PACK_TYPE 0402LF
J 0
(65 -900);
DISPLAY 0.510638 (65 -900);
FORCEPROP 1 LAST PART_NUMBER CS31002FB08
J 0
(65 -850);
DISPLAY 0.510638 (65 -850);
DISPLAY INVISIBLE (65 -850);
FORCEPROP 1 LAST PATH I192
J 0
(75 -550);
DISPLAY 0.978723 (75 -550);
PAINT WHITE (75 -550);
DISPLAY INVISIBLE (75 -550);
FORCEPROP 2 LAST CDS_LIB pure_quanta
J 0
(25 -725);
DISPLAY INVISIBLE (25 -725);
FORCEADD Q_RES..2
(0 -250);
FORCEPROP 1 LAST LOCATION R3506
J 0
(45 -125);
DISPLAY 0.978723 (45 -125);
FORCEPROP 0 LAST $SEC 1
J 0
(50 -75);
DISPLAY 0.680851 (50 -75);
PAINT MONO (50 -75);
DISPLAY INVISIBLE (50 -75);
FORCEPROP 0 LAST CDS_SEC 1
J 0
(50 -75);
DISPLAY 1.021277 (50 -75);
DISPLAY INVISIBLE (50 -75);
FORCEPROP 1 LASTPIN (0 -150) $PN 1
J 0
(5 -188);
DISPLAY 0.787234 (5 -188);
PAINT MONO (5 -188);
FORCEPROP 1 LASTPIN (0 -350) $PN 2
J 0
(5 -340);
DISPLAY 0.787234 (5 -340);
PAINT MONO (5 -340);
FORCEPROP 1 LAST MATERIAL EMPTY
J 0
(40 -325);
DISPLAY 0.638298 (40 -325);
PAINT RED (40 -325);
FORCEPROP 1 LAST VALUE 4.7K
J 0
(45 -175);
DISPLAY 0.638298 (45 -175);
FORCEPROP 1 LAST PACK_TYPE 0402LF
J 0
(40 -375);
DISPLAY 0.638298 (40 -375);
FORCEPROP 1 LAST TOLERANCE 5%
J 0
(45 -225);
DISPLAY 0.638298 (45 -225);
FORCEPROP 1 LAST WATTAGE 1/16W
J 0
(40 -275);
DISPLAY 0.638298 (40 -275);
FORCEPROP 1 LAST PART_NUMBER CS24702JB10
J 0
(40 -425);
DISPLAY 0.638298 (40 -425);
DISPLAY INVISIBLE (40 -425);
FORCEPROP 1 LAST PATH I193
J 0
(50 -75);
DISPLAY 0.978723 (50 -75);
PAINT WHITE (50 -75);
DISPLAY INVISIBLE (50 -75);
FORCEPROP 2 LAST CDS_LIB pure_quanta
J 0
(0 -250);
DISPLAY INVISIBLE (0 -250);
FORCEADD Q_RES..2
(2625 325);
FORCEPROP 1 LAST LOCATION R3508
J 0
(2670 450);
DISPLAY 0.978723 (2670 450);
FORCEPROP 0 LAST $SEC 1
J 0
(2675 500);
DISPLAY 0.680851 (2675 500);
PAINT MONO (2675 500);
DISPLAY INVISIBLE (2675 500);
FORCEPROP 0 LAST CDS_SEC 1
J 0
(2675 500);
DISPLAY 1.021277 (2675 500);
DISPLAY INVISIBLE (2675 500);
FORCEPROP 1 LASTPIN (2625 425) $PN 1
J 0
(2630 387);
DISPLAY 0.787234 (2630 387);
PAINT MONO (2630 387);
FORCEPROP 1 LASTPIN (2625 225) $PN 2
J 0
(2630 235);
DISPLAY 0.787234 (2630 235);
PAINT MONO (2630 235);
FORCEPROP 1 LAST VALUE 54.9K
J 0
(2670 400);
DISPLAY 0.787234 (2670 400);
FORCEPROP 1 LAST TOLERANCE 1%
J 0
(2670 350);
DISPLAY 0.787234 (2670 350);
FORCEPROP 1 LAST PACK_TYPE 0402LF
J 0
(2665 150);
DISPLAY 0.787234 (2665 150);
FORCEPROP 1 LAST MATERIAL CHIP
J 0
(2665 250);
DISPLAY 0.787234 (2665 250);
FORCEPROP 1 LAST WATTAGE 1/16W
J 0
(2665 300);
DISPLAY 0.787234 (2665 300);
FORCEPROP 1 LAST PART_NUMBER CS35492FB03
J 0
(2665 200);
DISPLAY 0.787234 (2665 200);
DISPLAY INVISIBLE (2665 200);
FORCEPROP 1 LAST PATH I194
J 0
(2675 500);
DISPLAY 0.978723 (2675 500);
PAINT WHITE (2675 500);
DISPLAY INVISIBLE (2675 500);
FORCEPROP 2 LAST CDS_LIB pure_quanta
J 0
(2625 325);
DISPLAY INVISIBLE (2625 325);
FORCEADD 74LVC1G126SE7..1
(2000 -1950);
FORCEPROP 1 LAST LOCATION U204
J 0
(2106 -2119);
DISPLAY 0.723404 (2106 -2119);
PAINT GREEN (2106 -2119);
FORCEPROP 0 LAST $SEC 1
J 0
(2125 -1725);
DISPLAY 0.680851 (2125 -1725);
PAINT MONO (2125 -1725);
DISPLAY INVISIBLE (2125 -1725);
FORCEPROP 0 LAST CDS_SEC 1
J 0
(2125 -1725);
DISPLAY 1.021277 (2125 -1725);
DISPLAY INVISIBLE (2125 -1725);
FORCEPROP 0 LASTPIN (1750 -1900) $PN 2
J 2
(1740 -1890);
DISPLAY 0.680851 (1740 -1890);
PAINT MONO (1740 -1890);
FORCEPROP 0 LASTPIN (2000 -2200) $PN 3
R 1
J 2
(1990 -2210);
DISPLAY 0.680851 (1990 -2210);
PAINT MONO (1990 -2210);
FORCEPROP 0 LASTPIN (1750 -2000) $PN 1
J 2
(1740 -1990);
DISPLAY 0.680851 (1740 -1990);
PAINT MONO (1740 -1990);
FORCEPROP 0 LASTPIN (2000 -1700) $PN 5
R 1
J 0
(1990 -1690);
DISPLAY 0.680851 (1990 -1690);
PAINT MONO (1990 -1690);
FORCEPROP 0 LASTPIN (2250 -1950) $PN 4
J 0
(2260 -1940);
DISPLAY 0.680851 (2260 -1940);
PAINT MONO (2260 -1940);
FORCEPROP 2 LAST PART_TYPE SMLF
J 0
(2125 -1775);
DISPLAY 0.638298 (2125 -1775);
FORCEPROP 1 LAST MATERIAL IC
J 0
(2075 -2300);
DISPLAY 0.723404 (2075 -2300);
PAINT GREEN (2075 -2300);
FORCEPROP 2 LAST VALUE 74LVC1G126SE-7
J 0
(2025 -1800);
DISPLAY 0.638298 (2025 -1800);
FORCEPROP 1 LAST PART_NUMBER AL1G0126009
J 0
(2081 -2241);
DISPLAY 0.723404 (2081 -2241);
PAINT GREEN (2081 -2241);
DISPLAY INVISIBLE (2081 -2241);
FORCEPROP 1 LAST PATH I195
J 0
(2000 -1950);
DISPLAY 0.723404 (2000 -1950);
PAINT GREEN (2000 -1950);
DISPLAY INVISIBLE (2000 -1950);
FORCEPROP 1 LAST NEEDS_NO_SIZE TRUE
J 0
(2000 -1950);
DISPLAY 0.723404 (2000 -1950);
PAINT GREEN (2000 -1950);
DISPLAY INVISIBLE (2000 -1950);
FORCEPROP 1 LAST CDS_LMAN_SYM_OUTLINE -100,100,100,-100
J 0
(2000 -1950);
DISPLAY 0.468085 (2000 -1950);
PAINT GREEN (2000 -1950);
DISPLAY INVISIBLE (2000 -1950);
FORCEPROP 2 LAST CDS_LIB pure_quanta
J 0
(2000 -1950);
DISPLAY INVISIBLE (2000 -1950);
FORCEADD UNIVERSAL_GND..1
(2000 -2350);
FORCEPROP 3 LASTPIN (2000 -2300) SIG_NAME GND\g
J 0
(2010 -2290);
DISPLAY 0.659574 (2010 -2290);
PAINT MONO (2010 -2290);
DISPLAY INVISIBLE (2010 -2290);
FORCEPROP 1 LAST PATH I196
J 0
(2075 -2350);
DISPLAY 0.872340 (2075 -2350);
PAINT AQUA (2075 -2350);
DISPLAY INVISIBLE (2075 -2350);
FORCEPROP 1 LAST HDL_POWER GND
J 1
(2025 -2425);
DISPLAY 0.872340 (2025 -2425);
PAINT GREEN (2025 -2425);
DISPLAY INVISIBLE (2025 -2425);
FORCEPROP 2 LAST CDS_LIB pure_quanta_power
J 0
(2000 -2350);
DISPLAY INVISIBLE (2000 -2350);
FORCEADD Q_RES..1
(3200 -1950);
FORCEPROP 1 LAST LOCATION R3036
J 0
(3000 -1950);
DISPLAY 0.638298 (3000 -1950);
FORCEPROP 0 LAST $SEC 1
J 0
(3450 -1900);
DISPLAY 0.680851 (3450 -1900);
PAINT MONO (3450 -1900);
DISPLAY INVISIBLE (3450 -1900);
FORCEPROP 0 LAST CDS_SEC 1
J 0
(3450 -1900);
DISPLAY 1.021277 (3450 -1900);
DISPLAY INVISIBLE (3450 -1900);
FORCEPROP 1 LASTPIN (3100 -1950) $PN 1
J 0
(3112 -1938);
DISPLAY 0.787234 (3112 -1938);
PAINT MONO (3112 -1938);
FORCEPROP 1 LASTPIN (3300 -1950) $PN 2
J 0
(3262 -1938);
DISPLAY 0.787234 (3262 -1938);
PAINT MONO (3262 -1938);
FORCEPROP 1 LAST MATERIAL CHIP
J 0
(3225 -2000);
DISPLAY 0.723404 (3225 -2000);
FORCEPROP 1 LAST VALUE 33.2
J 2
(3450 -1950);
DISPLAY 0.723404 (3450 -1950);
FORCEPROP 1 LAST PACK_TYPE 0402LF
J 0
(3025 -2000);
DISPLAY 0.723404 (3025 -2000);
FORCEPROP 1 LAST PART_NUMBER CS03322FB03
J 0
(2800 -2050);
DISPLAY 0.723404 (2800 -2050);
PAINT WHITE (2800 -2050);
DISPLAY INVISIBLE (2800 -2050);
FORCEPROP 1 LAST PATH I197
J 0
(3150 -1800);
DISPLAY 0.978723 (3150 -1800);
PAINT WHITE (3150 -1800);
DISPLAY INVISIBLE (3150 -1800);
FORCEPROP 2 LAST CDS_LIB pure_quanta
J 0
(3200 -1950);
DISPLAY INVISIBLE (3200 -1950);
FORCEPROP 1 LAST TOLERANCE 1%
J 0
(3675 -1950);
DISPLAY 0.723404 (3675 -1950);
PAINT SKYBLUE (3675 -1950);
DISPLAY INVISIBLE (3675 -1950);
FORCEPROP 1 LAST WATTAGE 1/16W
J 2
(3600 -2000);
DISPLAY 0.723404 (3600 -2000);
PAINT SKYBLUE (3600 -2000);
DISPLAY INVISIBLE (3600 -2000);
FORCEADD Q_RES..2
(0 2150);
FORCEPROP 1 LAST LOCATION R2909
J 0
(45 2275);
DISPLAY 0.978723 (45 2275);
FORCEPROP 0 LAST $SEC 1
J 0
(50 2325);
DISPLAY 0.680851 (50 2325);
PAINT MONO (50 2325);
DISPLAY INVISIBLE (50 2325);
FORCEPROP 0 LAST CDS_SEC 1
J 0
(50 2325);
DISPLAY 1.021277 (50 2325);
DISPLAY INVISIBLE (50 2325);
FORCEPROP 1 LASTPIN (0 2250) $PN 1
J 0
(5 2212);
DISPLAY 0.787234 (5 2212);
PAINT MONO (5 2212);
FORCEPROP 1 LASTPIN (0 2050) $PN 2
J 0
(5 2060);
DISPLAY 0.787234 (5 2060);
PAINT MONO (5 2060);
FORCEPROP 1 LAST VALUE 4.7K
J 0
(45 2225);
DISPLAY 0.638298 (45 2225);
FORCEPROP 1 LAST WATTAGE 1/16W
J 0
(40 2125);
DISPLAY 0.638298 (40 2125);
FORCEPROP 1 LAST TOLERANCE 5%
J 0
(45 2175);
DISPLAY 0.638298 (45 2175);
FORCEPROP 1 LAST MATERIAL CHIP
J 0
(40 2075);
DISPLAY 0.638298 (40 2075);
FORCEPROP 1 LAST PACK_TYPE 0402LF
J 0
(40 2025);
DISPLAY 0.638298 (40 2025);
FORCEPROP 1 LAST PART_NUMBER CS24702JB10
J 0
(40 1975);
DISPLAY 0.638298 (40 1975);
DISPLAY INVISIBLE (40 1975);
FORCEPROP 1 LAST PATH I198
J 0
(50 2325);
DISPLAY 0.978723 (50 2325);
PAINT WHITE (50 2325);
DISPLAY INVISIBLE (50 2325);
FORCEPROP 2 LAST CDS_LIB pure_quanta
J 0
(0 2150);
DISPLAY INVISIBLE (0 2150);
FORCEADD UNIVERSAL_POWER..1
(650 -1250);
FORCEPROP 3 LASTPIN (650 -1300) SIG_NAME P3V3_AUX\g
J 0
(660 -1290);
DISPLAY 0.659574 (660 -1290);
PAINT MONO (660 -1290);
DISPLAY INVISIBLE (660 -1290);
FORCEPROP 1 LAST HDL_POWER P3V3_AUX
J 1
(650 -1200);
DISPLAY 0.872340 (650 -1200);
PAINT GREEN (650 -1200);
FORCEPROP 1 LAST PATH I199
J 0
(700 -1225);
DISPLAY 0.872340 (700 -1225);
PAINT AQUA (700 -1225);
DISPLAY INVISIBLE (700 -1225);
FORCEPROP 2 LAST CDS_LIB pure_quanta_power
J 0
(650 -1250);
DISPLAY INVISIBLE (650 -1250);
FORCEADD Q_RES..2
(650 -1575);
FORCEPROP 1 LAST LOCATION R4515
J 0
(695 -1450);
DISPLAY 0.787234 (695 -1450);
FORCEPROP 0 LAST $SEC 1
J 0
(700 -1400);
DISPLAY 0.680851 (700 -1400);
PAINT MONO (700 -1400);
DISPLAY INVISIBLE (700 -1400);
FORCEPROP 0 LAST CDS_SEC 1
J 0
(700 -1400);
DISPLAY 1.021277 (700 -1400);
DISPLAY INVISIBLE (700 -1400);
FORCEPROP 1 LASTPIN (650 -1475) $PN 1
J 0
(655 -1513);
DISPLAY 0.787234 (655 -1513);
PAINT MONO (655 -1513);
FORCEPROP 1 LASTPIN (650 -1675) $PN 2
J 0
(655 -1665);
DISPLAY 0.787234 (655 -1665);
PAINT MONO (655 -1665);
FORCEPROP 1 LAST WATTAGE 1/16W
J 0
(690 -1600);
DISPLAY 0.510638 (690 -1600);
FORCEPROP 1 LAST MATERIAL CHIP
J 0
(690 -1650);
DISPLAY 0.510638 (690 -1650);
FORCEPROP 1 LAST TOLERANCE 1%
J 0
(695 -1550);
DISPLAY 0.510638 (695 -1550);
FORCEPROP 1 LAST PACK_TYPE 0402LF
J 0
(690 -1750);
DISPLAY 0.510638 (690 -1750);
FORCEPROP 1 LAST VALUE 100K
J 0
(695 -1500);
DISPLAY 0.510638 (695 -1500);
FORCEPROP 1 LAST PART_NUMBER CS41002FB09
J 0
(690 -1700);
DISPLAY 0.510638 (690 -1700);
DISPLAY INVISIBLE (690 -1700);
FORCEPROP 1 LAST PATH I200
J 0
(700 -1400);
DISPLAY 0.978723 (700 -1400);
PAINT WHITE (700 -1400);
DISPLAY INVISIBLE (700 -1400);
FORCEPROP 2 LAST CDS_LIB pure_quanta
J 0
(650 -1575);
DISPLAY INVISIBLE (650 -1575);
FORCEADD UNIVERSAL_POWER..1
(2950 -1300);
FORCEPROP 3 LASTPIN (2950 -1350) SIG_NAME P3V3_AUX\g
J 0
(2960 -1340);
DISPLAY 0.659574 (2960 -1340);
PAINT MONO (2960 -1340);
DISPLAY INVISIBLE (2960 -1340);
FORCEPROP 1 LAST HDL_POWER P3V3_AUX
J 1
(2950 -1250);
DISPLAY 0.872340 (2950 -1250);
PAINT GREEN (2950 -1250);
FORCEPROP 1 LAST PATH I201
J 0
(3000 -1275);
DISPLAY 0.872340 (3000 -1275);
PAINT AQUA (3000 -1275);
DISPLAY INVISIBLE (3000 -1275);
FORCEPROP 2 LAST CDS_LIB pure_quanta_power
J 0
(2950 -1300);
DISPLAY INVISIBLE (2950 -1300);
FORCEADD Q_RES..2
(2625 1575);
FORCEPROP 1 LAST LOCATION R2927
J 0
(2670 1700);
DISPLAY 0.978723 (2670 1700);
FORCEPROP 0 LAST $SEC 1
J 0
(2675 1750);
DISPLAY 0.680851 (2675 1750);
PAINT MONO (2675 1750);
DISPLAY INVISIBLE (2675 1750);
FORCEPROP 0 LAST CDS_SEC 1
J 0
(2675 1750);
DISPLAY 1.021277 (2675 1750);
DISPLAY INVISIBLE (2675 1750);
FORCEPROP 1 LASTPIN (2625 1675) $PN 1
J 0
(2630 1637);
DISPLAY 0.787234 (2630 1637);
PAINT MONO (2630 1637);
FORCEPROP 1 LASTPIN (2625 1475) $PN 2
J 0
(2630 1485);
DISPLAY 0.787234 (2630 1485);
PAINT MONO (2630 1485);
FORCEPROP 1 LAST TOLERANCE 1%
J 0
(2670 1600);
DISPLAY 0.510638 (2670 1600);
FORCEPROP 1 LAST VALUE 100K
J 0
(2670 1650);
DISPLAY 0.510638 (2670 1650);
FORCEPROP 1 LAST PACK_TYPE 0402LF
J 0
(2665 1400);
DISPLAY 0.510638 (2665 1400);
FORCEPROP 1 LAST WATTAGE 1/16W
J 0
(2665 1550);
DISPLAY 0.510638 (2665 1550);
FORCEPROP 1 LAST MATERIAL CHIP
J 0
(2665 1500);
DISPLAY 0.510638 (2665 1500);
FORCEPROP 1 LAST PART_NUMBER CS41002FB09
J 0
(2665 1450);
DISPLAY 0.510638 (2665 1450);
DISPLAY INVISIBLE (2665 1450);
FORCEPROP 1 LAST PATH I203
J 0
(2675 1750);
DISPLAY 0.978723 (2675 1750);
PAINT WHITE (2675 1750);
DISPLAY INVISIBLE (2675 1750);
FORCEPROP 2 LAST CDS_LIB pure_quanta
J 0
(2625 1575);
DISPLAY INVISIBLE (2625 1575);
FORCEADD Q_RES..2
(2950 -1625);
FORCEPROP 1 LAST LOCATION R4173
J 0
(2995 -1500);
DISPLAY 0.978723 (2995 -1500);
FORCEPROP 0 LAST $SEC 1
J 0
(3000 -1450);
DISPLAY 0.680851 (3000 -1450);
PAINT MONO (3000 -1450);
DISPLAY INVISIBLE (3000 -1450);
FORCEPROP 0 LAST CDS_SEC 1
J 0
(3000 -1450);
DISPLAY 0.680851 (3000 -1450);
DISPLAY INVISIBLE (3000 -1450);
FORCEPROP 1 LASTPIN (2950 -1525) $PN 1
J 0
(2955 -1563);
DISPLAY 0.787234 (2955 -1563);
PAINT MONO (2955 -1563);
FORCEPROP 1 LASTPIN (2950 -1725) $PN 2
J 0
(2955 -1715);
DISPLAY 0.787234 (2955 -1715);
PAINT MONO (2955 -1715);
FORCEPROP 1 LAST TOLERANCE 1%
J 0
(2995 -1600);
DISPLAY 0.510638 (2995 -1600);
FORCEPROP 1 LAST WATTAGE 1/16W
J 0
(2990 -1650);
DISPLAY 0.510638 (2990 -1650);
FORCEPROP 1 LAST VALUE 100K
J 0
(2995 -1550);
DISPLAY 0.510638 (2995 -1550);
FORCEPROP 1 LAST PACK_TYPE 0402LF
J 0
(2990 -1800);
DISPLAY 0.510638 (2990 -1800);
FORCEPROP 1 LAST MATERIAL EMPTY
J 0
(2990 -1700);
DISPLAY 0.510638 (2990 -1700);
PAINT RED (2990 -1700);
FORCEPROP 1 LAST PART_NUMBER CS41002FB09
J 0
(2990 -1750);
DISPLAY 0.510638 (2990 -1750);
DISPLAY INVISIBLE (2990 -1750);
FORCEPROP 1 LAST PATH I204
J 0
(3000 -1450);
DISPLAY 0.978723 (3000 -1450);
PAINT WHITE (3000 -1450);
DISPLAY INVISIBLE (3000 -1450);
FORCEPROP 2 LAST CDS_LIB pure_quanta
J 0
(2950 -1625);
DISPLAY INVISIBLE (2950 -1625);
FORCEADD 74LVC2G17GW..1
(1475 2450);
FORCEPROP 1 LAST LOCATION U195
J 0
(1702 2210);
DISPLAY 0.723404 (1702 2210);
PAINT GREEN (1702 2210);
FORCEPROP 0 LAST $SEC 1
J 0
(1725 2250);
DISPLAY 0.680851 (1725 2250);
PAINT MONO (1725 2250);
DISPLAY INVISIBLE (1725 2250);
FORCEPROP 0 LAST CDS_SEC 1
J 0
(1725 2250);
DISPLAY 1.021277 (1725 2250);
DISPLAY INVISIBLE (1725 2250);
FORCEPROP 0 LASTPIN (1100 2575) $PN 1
J 2
(1090 2585);
DISPLAY 0.680851 (1090 2585);
PAINT MONO (1090 2585);
FORCEPROP 0 LASTPIN (1100 2325) $PN 3
J 2
(1090 2335);
DISPLAY 0.680851 (1090 2335);
PAINT MONO (1090 2335);
FORCEPROP 0 LASTPIN (1850 2575) $PN 6
J 0
(1860 2585);
DISPLAY 0.680851 (1860 2585);
PAINT MONO (1860 2585);
FORCEPROP 0 LASTPIN (1850 2325) $PN 4
J 0
(1860 2335);
DISPLAY 0.680851 (1860 2335);
PAINT MONO (1860 2335);
FORCEPROP 0 LASTPIN (1500 2025) $PN 2
R 1
J 2
(1490 2015);
DISPLAY 0.680851 (1490 2015);
PAINT MONO (1490 2015);
FORCEPROP 0 LASTPIN (1500 2875) $PN 5
R 1
J 0
(1490 2885);
DISPLAY 0.680851 (1490 2885);
PAINT MONO (1490 2885);
FORCEPROP 2 LAST PART_TYPE SMLF
J 0
(1275 1775);
DISPLAY 1.021277 (1275 1775);
FORCEPROP 2 LAST VALUE 74LVC2G17GW
J 0
(1275 1725);
DISPLAY 1.021277 (1275 1725);
FORCEPROP 1 LAST MATERIAL IC
J 0
(1275 1625);
DISPLAY 0.723404 (1275 1625);
PAINT GREEN (1275 1625);
FORCEPROP 1 LAST PART_NUMBER AL2G0017005
J 0
(1275 1675);
DISPLAY 0.723404 (1275 1675);
PAINT GREEN (1275 1675);
DISPLAY INVISIBLE (1275 1675);
FORCEPROP 1 LAST PATH I65
J 0
(1700 2175);
DISPLAY 0.723404 (1700 2175);
PAINT GREEN (1700 2175);
DISPLAY INVISIBLE (1700 2175);
FORCEPROP 2 LAST CDS_LIB pure_quanta
J 0
(1475 2450);
DISPLAY INVISIBLE (1475 2450);
FORCEPROP 1 LAST NEEDS_NO_SIZE TRUE
J 0
(1700 2449);
DISPLAY 0.468085 (1700 2449);
PAINT GREEN (1700 2449);
DISPLAY INVISIBLE (1700 2449);
FORCEPROP 1 LAST CDS_LMAN_SYM_OUTLINE -225,275,225,-275
J 0
(1475 2450);
DISPLAY 0.468085 (1475 2450);
PAINT GREEN (1475 2450);
DISPLAY INVISIBLE (1475 2450);
FORCEADD UNIVERSAL_POWER..1
(0 3525);
FORCEPROP 3 LASTPIN (0 3475) SIG_NAME P3V3_AUX\g
J 0
(10 3485);
DISPLAY 0.659574 (10 3485);
PAINT MONO (10 3485);
DISPLAY INVISIBLE (10 3485);
FORCEPROP 1 LAST HDL_POWER P3V3_AUX
J 1
(0 3575);
DISPLAY 0.872340 (0 3575);
PAINT GREEN (0 3575);
FORCEPROP 1 LAST PATH I67
J 0
(50 3550);
DISPLAY 0.872340 (50 3550);
PAINT AQUA (50 3550);
DISPLAY INVISIBLE (50 3550);
FORCEPROP 2 LAST CDS_LIB pure_quanta_power
J 0
(0 3525);
PAINT MONO (0 3525);
DISPLAY INVISIBLE (0 3525);
FORCEADD Q_RES..2
(0 3275);
FORCEPROP 1 LAST LOCATION R2815
J 0
(45 3400);
DISPLAY 0.978723 (45 3400);
FORCEPROP 0 LAST $SEC 1
J 0
(50 3450);
DISPLAY 0.680851 (50 3450);
PAINT MONO (50 3450);
DISPLAY INVISIBLE (50 3450);
FORCEPROP 0 LAST CDS_SEC 1
J 0
(50 3450);
DISPLAY 1.021277 (50 3450);
DISPLAY INVISIBLE (50 3450);
FORCEPROP 1 LASTPIN (0 3375) $PN 1
J 0
(5 3337);
DISPLAY 0.787234 (5 3337);
PAINT MONO (5 3337);
FORCEPROP 1 LASTPIN (0 3175) $PN 2
J 0
(5 3185);
DISPLAY 0.787234 (5 3185);
PAINT MONO (5 3185);
FORCEPROP 1 LAST VALUE 100K
J 0
(45 3350);
DISPLAY 0.510638 (45 3350);
FORCEPROP 1 LAST PACK_TYPE 0402LF
J 0
(40 3100);
DISPLAY 0.510638 (40 3100);
FORCEPROP 1 LAST MATERIAL EMPTY
J 0
(40 3200);
DISPLAY 0.510638 (40 3200);
PAINT RED (40 3200);
FORCEPROP 1 LAST WATTAGE 1/16W
J 0
(40 3250);
DISPLAY 0.510638 (40 3250);
FORCEPROP 1 LAST TOLERANCE 1%
J 0
(45 3300);
DISPLAY 0.510638 (45 3300);
FORCEPROP 1 LAST PART_NUMBER CS41002FB09
J 0
(40 3150);
DISPLAY 0.510638 (40 3150);
DISPLAY INVISIBLE (40 3150);
FORCEPROP 1 LAST PATH I68
J 0
(50 3450);
DISPLAY 0.978723 (50 3450);
PAINT WHITE (50 3450);
DISPLAY INVISIBLE (50 3450);
FORCEPROP 2 LAST CDS_LIB pure_quanta
J 0
(0 3275);
DISPLAY INVISIBLE (0 3275);
FORCEADD UNIVERSAL_GND..1
(25 2600);
FORCEPROP 3 LASTPIN (25 2650) SIG_NAME GND\g
J 0
(35 2660);
DISPLAY 0.659574 (35 2660);
PAINT MONO (35 2660);
DISPLAY INVISIBLE (35 2660);
FORCEPROP 1 LAST PATH I69
J 0
(100 2600);
DISPLAY 0.872340 (100 2600);
PAINT AQUA (100 2600);
DISPLAY INVISIBLE (100 2600);
FORCEPROP 1 LAST HDL_POWER GND
J 1
(50 2525);
DISPLAY 0.872340 (50 2525);
PAINT GREEN (50 2525);
DISPLAY INVISIBLE (50 2525);
FORCEPROP 2 LAST CDS_LIB pure_quanta_power
J 0
(25 2600);
DISPLAY INVISIBLE (25 2600);
FORCEADD OFFPAGE..4
R 2
(-250 3000);
FORCEPROP 2 LAST $XR0 81 
J 0
(-471 3000);
DISPLAY 0.638298 (-471 3000);
PAINT MONO (-471 3000);
FORCEPROP 2 LAST PATH I70
J 0
(-500 3050);
DISPLAY 1.021277 (-500 3050);
DISPLAY INVISIBLE (-500 3050);
FORCEPROP 1 LAST COMMENT_BODY TRUE
J 2
(-225 2900);
DISPLAY 0.872340 (-225 2900);
PAINT GREEN (-225 2900);
DISPLAY INVISIBLE (-225 2900);
FORCEPROP 1 LAST OFFPAGE TRUE
J 2
(-575 2875);
DISPLAY 0.872340 (-575 2875);
PAINT GREEN (-575 2875);
DISPLAY INVISIBLE (-575 2875);
FORCEPROP 2 LAST CDS_LIB standard
J 0
(-250 3000);
DISPLAY INVISIBLE (-250 3000);
FORCEADD UNIVERSAL_POWER..1
(0 2400);
FORCEPROP 3 LASTPIN (0 2350) SIG_NAME P3V3_AUX\g
J 0
(10 2360);
DISPLAY 0.659574 (10 2360);
PAINT MONO (10 2360);
DISPLAY INVISIBLE (10 2360);
FORCEPROP 1 LAST HDL_POWER P3V3_AUX
J 1
(0 2450);
DISPLAY 0.872340 (0 2450);
PAINT GREEN (0 2450);
FORCEPROP 1 LAST PATH I71
J 0
(50 2425);
DISPLAY 0.872340 (50 2425);
PAINT AQUA (50 2425);
DISPLAY INVISIBLE (50 2425);
FORCEPROP 2 LAST CDS_LIB pure_quanta_power
J 0
(0 2400);
PAINT MONO (0 2400);
DISPLAY INVISIBLE (0 2400);
FORCEADD UNIVERSAL_GND..1
(25 1500);
FORCEPROP 3 LASTPIN (25 1550) SIG_NAME GND\g
J 0
(35 1560);
DISPLAY 0.659574 (35 1560);
PAINT MONO (35 1560);
DISPLAY INVISIBLE (35 1560);
FORCEPROP 1 LAST PATH I74
J 0
(100 1500);
DISPLAY 0.872340 (100 1500);
PAINT AQUA (100 1500);
DISPLAY INVISIBLE (100 1500);
FORCEPROP 1 LAST HDL_POWER GND
J 1
(50 1425);
DISPLAY 0.872340 (50 1425);
PAINT GREEN (50 1425);
DISPLAY INVISIBLE (50 1425);
FORCEPROP 2 LAST CDS_LIB pure_quanta_power
J 0
(25 1500);
DISPLAY INVISIBLE (25 1500);
FORCEADD OFFPAGE..4
R 2
(-200 1875);
FORCEPROP 2 LAST $XR0 246 
J 0
(-482 1875);
DISPLAY 0.638298 (-482 1875);
PAINT MONO (-482 1875);
FORCEPROP 2 LAST PATH I75
J 0
(-450 1925);
DISPLAY 1.021277 (-450 1925);
DISPLAY INVISIBLE (-450 1925);
FORCEPROP 1 LAST COMMENT_BODY TRUE
J 2
(-175 1775);
DISPLAY 0.872340 (-175 1775);
PAINT GREEN (-175 1775);
DISPLAY INVISIBLE (-175 1775);
FORCEPROP 1 LAST OFFPAGE TRUE
J 2
(-525 1750);
DISPLAY 0.872340 (-525 1750);
PAINT GREEN (-525 1750);
DISPLAY INVISIBLE (-525 1750);
FORCEPROP 2 LAST CDS_LIB standard
J 0
(-200 1875);
DISPLAY INVISIBLE (-200 1875);
FORCEADD UNIVERSAL_GND..1
(1500 1850);
FORCEPROP 3 LASTPIN (1500 1900) SIG_NAME GND\g
J 0
(1510 1910);
DISPLAY 0.659574 (1510 1910);
PAINT MONO (1510 1910);
DISPLAY INVISIBLE (1510 1910);
FORCEPROP 1 LAST PATH I76
J 0
(1575 1850);
DISPLAY 0.872340 (1575 1850);
PAINT AQUA (1575 1850);
DISPLAY INVISIBLE (1575 1850);
FORCEPROP 1 LAST HDL_POWER GND
J 1
(1525 1775);
DISPLAY 0.872340 (1525 1775);
PAINT GREEN (1525 1775);
DISPLAY INVISIBLE (1525 1775);
FORCEPROP 2 LAST CDS_LIB pure_quanta_power
J 0
(1500 1850);
DISPLAY INVISIBLE (1500 1850);
FORCEADD Q_RES..2
(2500 3225);
FORCEPROP 1 LAST LOCATION R2820
J 0
(2545 3350);
DISPLAY 0.638298 (2545 3350);
FORCEPROP 2 LAST $SEC 1
J 0
(2550 3450);
DISPLAY 0.680851 (2550 3450);
PAINT MONO (2550 3450);
DISPLAY INVISIBLE (2550 3450);
FORCEPROP 2 LAST CDS_SEC 1
J 0
(2550 3450);
DISPLAY 1.021277 (2550 3450);
DISPLAY INVISIBLE (2550 3450);
FORCEPROP 1 LASTPIN (2500 3325) $PN 1
J 0
(2505 3287);
DISPLAY 0.787234 (2505 3287);
FORCEPROP 1 LASTPIN (2500 3125) $PN 2
J 0
(2505 3135);
DISPLAY 0.787234 (2505 3135);
FORCEPROP 1 LAST VALUE 4.7K
J 0
(2545 3300);
DISPLAY 0.638298 (2545 3300);
FORCEPROP 1 LAST MATERIAL EMPTY
J 0
(2540 3150);
DISPLAY 0.638298 (2540 3150);
PAINT RED (2540 3150);
FORCEPROP 1 LAST WATTAGE 1/16W
J 0
(2540 3200);
DISPLAY 0.638298 (2540 3200);
FORCEPROP 1 LAST TOLERANCE 5%
J 0
(2545 3250);
DISPLAY 0.638298 (2545 3250);
FORCEPROP 1 LAST PACK_TYPE 0402LF
J 0
(2540 3100);
DISPLAY 0.638298 (2540 3100);
FORCEPROP 1 LAST PART_NUMBER CS24702JB10
J 0
(2540 3050);
DISPLAY 0.638298 (2540 3050);
DISPLAY INVISIBLE (2540 3050);
FORCEPROP 1 LAST PATH I78
J 0
(2550 3400);
DISPLAY 0.978723 (2550 3400);
PAINT WHITE (2550 3400);
DISPLAY INVISIBLE (2550 3400);
FORCEPROP 2 LAST CDS_LIB pure_quanta
J 0
(2500 3225);
PAINT MONO (2500 3225);
DISPLAY INVISIBLE (2500 3225);
FORCEADD OFFPAGE..2
(4125 3000);
FORCEPROP 2 LAST $XR0 119 
J 0
(4314 3000);
DISPLAY 0.638298 (4314 3000);
PAINT MONO (4314 3000);
FORCEPROP 2 LAST PATH I79
J 0
(4325 3050);
DISPLAY 1.021277 (4325 3050);
DISPLAY INVISIBLE (4325 3050);
FORCEPROP 1 LAST COMMENT_BODY TRUE
J 0
(4080 2905);
DISPLAY 0.872340 (4080 2905);
PAINT GREEN (4080 2905);
DISPLAY INVISIBLE (4080 2905);
FORCEPROP 1 LAST OFFPAGE TRUE
J 0
(4450 2875);
DISPLAY 0.872340 (4450 2875);
PAINT AQUA (4450 2875);
DISPLAY INVISIBLE (4450 2875);
FORCEPROP 2 LAST CDS_LIB standard
J 0
(4125 3000);
DISPLAY INVISIBLE (4125 3000);
FORCEADD UNIVERSAL_POWER..1
(2500 3475);
FORCEPROP 3 LASTPIN (2500 3425) SIG_NAME P3V3_AUX\g
J 0
(2510 3435);
DISPLAY 0.659574 (2510 3435);
PAINT MONO (2510 3435);
DISPLAY INVISIBLE (2510 3435);
FORCEPROP 1 LAST HDL_POWER P3V3_AUX
J 1
(2500 3525);
DISPLAY 0.872340 (2500 3525);
PAINT GREEN (2500 3525);
FORCEPROP 1 LAST PATH I80
J 0
(2550 3500);
DISPLAY 0.872340 (2550 3500);
PAINT AQUA (2550 3500);
DISPLAY INVISIBLE (2550 3500);
FORCEPROP 2 LAST CDS_LIB pure_quanta_power
J 0
(2500 3475);
PAINT MONO (2500 3475);
DISPLAY INVISIBLE (2500 3475);
FORCEADD OFFPAGE..2
(4125 1875);
FORCEPROP 2 LAST $XR0 115 
J 0
(4314 1875);
DISPLAY 0.638298 (4314 1875);
PAINT MONO (4314 1875);
FORCEPROP 2 LAST PATH I82
J 0
(4325 1925);
DISPLAY 1.021277 (4325 1925);
DISPLAY INVISIBLE (4325 1925);
FORCEPROP 1 LAST COMMENT_BODY TRUE
J 0
(4080 1780);
DISPLAY 0.872340 (4080 1780);
PAINT GREEN (4080 1780);
DISPLAY INVISIBLE (4080 1780);
FORCEPROP 1 LAST OFFPAGE TRUE
J 0
(4450 1750);
DISPLAY 0.872340 (4450 1750);
PAINT AQUA (4450 1750);
DISPLAY INVISIBLE (4450 1750);
FORCEPROP 2 LAST CDS_LIB standard
J 0
(4125 1875);
DISPLAY INVISIBLE (4125 1875);
FORCEADD UNIVERSAL_POWER..1
(2600 2300);
FORCEPROP 3 LASTPIN (2600 2250) SIG_NAME P3V3_AUX\g
J 0
(2610 2260);
DISPLAY 0.659574 (2610 2260);
PAINT MONO (2610 2260);
DISPLAY INVISIBLE (2610 2260);
FORCEPROP 1 LAST HDL_POWER P3V3_AUX
J 1
(2600 2350);
DISPLAY 0.872340 (2600 2350);
PAINT GREEN (2600 2350);
FORCEPROP 1 LAST PATH I83
J 0
(2650 2325);
DISPLAY 0.872340 (2650 2325);
PAINT AQUA (2650 2325);
DISPLAY INVISIBLE (2650 2325);
FORCEPROP 2 LAST CDS_LIB pure_quanta_power
J 0
(2600 2300);
PAINT MONO (2600 2300);
DISPLAY INVISIBLE (2600 2300);
FORCEADD UNIVERSAL_POWER..1
(1625 3700);
FORCEPROP 3 LASTPIN (1625 3650) SIG_NAME P3V3_AUX\g
J 0
(1635 3660);
DISPLAY 0.659574 (1635 3660);
PAINT MONO (1635 3660);
DISPLAY INVISIBLE (1635 3660);
FORCEPROP 1 LAST HDL_POWER P3V3_AUX
J 1
(1625 3750);
DISPLAY 0.872340 (1625 3750);
PAINT GREEN (1625 3750);
FORCEPROP 1 LAST PATH I87
J 0
(1675 3725);
DISPLAY 0.872340 (1675 3725);
PAINT AQUA (1675 3725);
DISPLAY INVISIBLE (1675 3725);
FORCEPROP 2 LAST CDS_LIB pure_quanta_power
J 0
(1625 3700);
PAINT MONO (1625 3700);
DISPLAY INVISIBLE (1625 3700);
FORCEADD UNIVERSAL_GND..1
(1625 3150);
FORCEPROP 3 LASTPIN (1625 3200) SIG_NAME GND\g
J 0
(1635 3210);
DISPLAY 0.659574 (1635 3210);
PAINT MONO (1635 3210);
DISPLAY INVISIBLE (1635 3210);
FORCEPROP 1 LAST PATH I88
J 0
(1700 3150);
DISPLAY 0.872340 (1700 3150);
PAINT AQUA (1700 3150);
DISPLAY INVISIBLE (1700 3150);
FORCEPROP 1 LAST HDL_POWER GND
J 1
(1650 3075);
DISPLAY 0.872340 (1650 3075);
PAINT GREEN (1650 3075);
DISPLAY INVISIBLE (1650 3075);
FORCEPROP 2 LAST CDS_LIB pure_quanta_power
J 0
(1625 3150);
PAINT MONO (1625 3150);
DISPLAY INVISIBLE (1625 3150);
FORCEADD Q_CAP..1
(1625 3375);
FORCEPROP 1 LAST LOCATION C1769
J 0
(1675 3475);
DISPLAY 0.787234 (1675 3475);
FORCEPROP 2 LAST $SEC 1
J 0
(1675 3575);
DISPLAY 0.680851 (1675 3575);
PAINT MONO (1675 3575);
DISPLAY INVISIBLE (1675 3575);
FORCEPROP 2 LAST CDS_SEC 1
J 0
(1675 3575);
DISPLAY 1.021277 (1675 3575);
DISPLAY INVISIBLE (1675 3575);
FORCEPROP 1 LASTPIN (1625 3475) $PN 1
J 0
(1635 3455);
DISPLAY 0.787234 (1635 3455);
FORCEPROP 1 LASTPIN (1625 3275) $PN 2
J 0
(1635 3255);
DISPLAY 0.787234 (1635 3255);
FORCEPROP 1 LAST PACK_TYPE 0402
J 0
(1675 3175);
DISPLAY 0.510638 (1675 3175);
FORCEPROP 1 LAST MATERIAL X7R
J 0
(1675 3275);
DISPLAY 0.510638 (1675 3275);
FORCEPROP 1 LAST TOLERANCE 10%
J 0
(1675 3325);
DISPLAY 0.510638 (1675 3325);
FORCEPROP 1 LAST VOLTAGE 25V
J 0
(1675 3375);
DISPLAY 0.510638 (1675 3375);
FORCEPROP 1 LAST VALUE 0.1UF
J 0
(1675 3425);
DISPLAY 0.510638 (1675 3425);
FORCEPROP 1 LAST PART_NUMBER CH4104K1B00
J 0
(1675 3225);
DISPLAY 0.510638 (1675 3225);
DISPLAY INVISIBLE (1675 3225);
FORCEPROP 1 LAST PATH I89
J 0
(1675 3525);
DISPLAY 0.978723 (1675 3525);
PAINT WHITE (1675 3525);
DISPLAY INVISIBLE (1675 3525);
FORCEPROP 2 LAST CDS_LIB pure_quanta
J 2
(1625 3375);
PAINT MONO (1625 3375);
DISPLAY INVISIBLE (1625 3375);
FORCEADD Q_RES..2
(25 2800);
FORCEPROP 1 LAST LOCATION R2915
J 0
(70 2925);
DISPLAY 0.638298 (70 2925);
FORCEPROP 2 LAST $SEC 1
J 0
(75 3025);
DISPLAY 0.680851 (75 3025);
PAINT MONO (75 3025);
DISPLAY INVISIBLE (75 3025);
FORCEPROP 2 LAST CDS_SEC 1
J 0
(75 3025);
DISPLAY 1.021277 (75 3025);
DISPLAY INVISIBLE (75 3025);
FORCEPROP 1 LASTPIN (25 2900) $PN 1
J 0
(30 2862);
DISPLAY 0.787234 (30 2862);
FORCEPROP 1 LASTPIN (25 2700) $PN 2
J 0
(30 2710);
DISPLAY 0.787234 (30 2710);
FORCEPROP 1 LAST PACK_TYPE 0402LF
J 0
(65 2675);
DISPLAY 0.638298 (65 2675);
FORCEPROP 1 LAST MATERIAL CHIP
J 0
(65 2725);
DISPLAY 0.638298 (65 2725);
FORCEPROP 1 LAST WATTAGE 1/16W
J 0
(65 2775);
DISPLAY 0.638298 (65 2775);
FORCEPROP 1 LAST TOLERANCE 5%
J 0
(70 2825);
DISPLAY 0.638298 (70 2825);
FORCEPROP 1 LAST VALUE 4.7K
J 0
(70 2875);
DISPLAY 0.638298 (70 2875);
FORCEPROP 1 LAST PART_NUMBER CS24702JB10
J 0
(65 2625);
DISPLAY 0.638298 (65 2625);
DISPLAY INVISIBLE (65 2625);
FORCEPROP 1 LAST PATH I92
J 0
(75 2975);
DISPLAY 0.978723 (75 2975);
PAINT WHITE (75 2975);
DISPLAY INVISIBLE (75 2975);
FORCEPROP 2 LAST CDS_LIB pure_quanta
J 0
(25 2800);
PAINT MONO (25 2800);
DISPLAY INVISIBLE (25 2800);
FORCEADD Q_RES..2
(25 1675);
FORCEPROP 1 LAST LOCATION R2916
J 0
(70 1800);
DISPLAY 0.638298 (70 1800);
FORCEPROP 2 LAST $SEC 1
J 0
(75 1900);
DISPLAY 0.680851 (75 1900);
PAINT MONO (75 1900);
DISPLAY INVISIBLE (75 1900);
FORCEPROP 2 LAST CDS_SEC 1
J 0
(75 1900);
DISPLAY 1.021277 (75 1900);
DISPLAY INVISIBLE (75 1900);
FORCEPROP 1 LASTPIN (25 1775) $PN 1
J 0
(30 1737);
DISPLAY 0.787234 (30 1737);
FORCEPROP 1 LASTPIN (25 1575) $PN 2
J 0
(30 1585);
DISPLAY 0.787234 (30 1585);
FORCEPROP 1 LAST PACK_TYPE 0402LF
J 0
(65 1550);
DISPLAY 0.638298 (65 1550);
FORCEPROP 1 LAST VALUE 4.7K
J 0
(70 1750);
DISPLAY 0.638298 (70 1750);
FORCEPROP 1 LAST WATTAGE 1/16W
J 0
(65 1650);
DISPLAY 0.638298 (65 1650);
FORCEPROP 1 LAST MATERIAL EMPTY
J 0
(65 1600);
DISPLAY 0.638298 (65 1600);
PAINT RED (65 1600);
FORCEPROP 1 LAST TOLERANCE 5%
J 0
(70 1700);
DISPLAY 0.638298 (70 1700);
FORCEPROP 1 LAST PART_NUMBER CS24702JB10
J 0
(65 1500);
DISPLAY 0.638298 (65 1500);
DISPLAY INVISIBLE (65 1500);
FORCEPROP 1 LAST PATH I93
J 0
(75 1850);
DISPLAY 0.978723 (75 1850);
PAINT WHITE (75 1850);
DISPLAY INVISIBLE (75 1850);
FORCEPROP 2 LAST CDS_LIB pure_quanta
J 0
(25 1675);
PAINT MONO (25 1675);
DISPLAY INVISIBLE (25 1675);
FORCEADD QUANTA_TITLE_BLOCK_C..1
(6375 -2675);
FORCEPROP 0 LAST CDS_CON_LAST_MODIFIED Thu Sep 14 16:12:24 2023
J 0
(4490 -2660);
PAINT MONO (4490 -2660);
DISPLAY INVISIBLE (4490 -2660);
FORCEPROP 1 LAST CUSTOM_TXT_CDS <CON_LAST_MODIFIED>
J 0
(4490 -2660);
DISPLAY 0.978723 (4490 -2660);
FORCEPROP 2 LAST CUSTOM_TXT_CDS <XR_PAGE_TITLE>
J 0
(-1515 2575);
DISPLAY 0.638298 (-1515 2575);
PAINT PINK (-1515 2575);
DISPLAY INVISIBLE (-1515 2575);
FORCEPROP 2 LAST CUSTOM_TXT_CDS <Q_NUMBER>
J 0
(4972 -2572);
DISPLAY 1.212766 (4972 -2572);
FORCEPROP 1 LAST CUSTOM_TXT_CDS <NAME_2>
J 0
(3200 -2625);
FORCEPROP 1 LAST CUSTOM_TXT_CDS <NAME_1>
J 0
(3200 -2500);
FORCEPROP 1 LAST CUSTOM_TXT_CDS <Q_PROJ>
J 0
(3993 -2573);
DISPLAY 1.212766 (3993 -2573);
FORCEPROP 1 LAST CUSTOM_TXT_CDS <Q_REV>
J 0
(6191 -2572);
DISPLAY 1.212766 (6191 -2572);
FORCEPROP 1 LAST CUSTOM_TXT_CDS <CON_PAGE_NUM> OF <CON_TOTAL_PAGES>
J 0
(5929 -2657);
DISPLAY 0.978723 (5929 -2657);
FORCEPROP 1 LAST Q_TITLE EXAMAX_ISO (7/7)
J 0
(-2991 -2649);
DISPLAY 1.957447 (-2991 -2649);
PAINT GREEN (-2991 -2649);
FORCEPROP 1 LAST COMMENT_BODY TRUE
J 0
(6387 -2688);
DISPLAY 0.978723 (6387 -2688);
PAINT GREEN (6387 -2688);
DISPLAY INVISIBLE (6387 -2688);
FORCEPROP 1 LAST Q_DEPT BU9
J 1
(2612 -2626);
DISPLAY 1.957447 (2612 -2626);
PAINT GREEN (2612 -2626);
DISPLAY INVISIBLE (2612 -2626);
FORCEPROP 2 LAST CDS_XR_PAGE_TITLE CR-130 : @T6G_MB_LIB.T6G(SCH_1):PAGE130
J 0
(-1515 2575);
DISPLAY 0.638298 (-1515 2575);
PAINT PINK (-1515 2575);
DISPLAY INVISIBLE (-1515 2575);
FORCEPROP 2 LAST CDS_LIB pure_quanta
J 0
(6375 -2675);
PAINT MONO (6375 -2675);
DISPLAY INVISIBLE (6375 -2675);
FORCEPROP 1 LAST CDS_LMAN_SYM_OUTLINE -9475,6775,100,-125
J 0
(6375 -2675);
DISPLAY 0.468085 (6375 -2675);
PAINT GREEN (6375 -2675);
DISPLAY INVISIBLE (6375 -2675);
FORCEPROP 2 LAST PAGE_BORDER TRUE
J 0
(-1515 2575);
DISPLAY 0.638298 (-1515 2575);
PAINT PINK (-1515 2575);
DISPLAY INVISIBLE (-1515 2575);
FORCEADD DNS..2
(2925 -1625);
PAINT RED (2925 -1625);
FORCEPROP 1 LAST COMMENT_BODY TRUE
J 0
(2925 -1625);
DISPLAY INVISIBLE (2925 -1625);
FORCEPROP 2 LAST CDS_LIB mstr_misc
J 0
(2925 -1625);
DISPLAY INVISIBLE (2925 -1625);
FORCEADD DNS..2
(2650 -350);
PAINT RED (2650 -350);
FORCEPROP 1 LAST COMMENT_BODY TRUE
J 0
(2650 -350);
DISPLAY INVISIBLE (2650 -350);
FORCEPROP 2 LAST CDS_LIB mstr_misc
J 0
(2650 -350);
DISPLAY INVISIBLE (2650 -350);
FORCEADD DNS..2
(2500 3200);
PAINT RED (2500 3200);
FORCEPROP 1 LAST COMMENT_BODY TRUE
J 0
(2500 3200);
DISPLAY INVISIBLE (2500 3200);
FORCEPROP 2 LAST CDS_LIB mstr_misc
J 0
(2500 3200);
DISPLAY INVISIBLE (2500 3200);
FORCEADD DNS..2
(25 1650);
PAINT RED (25 1650);
FORCEPROP 1 LAST COMMENT_BODY TRUE
J 0
(25 1650);
DISPLAY INVISIBLE (25 1650);
FORCEPROP 2 LAST CDS_LIB mstr_misc
J 0
(25 1650);
DISPLAY INVISIBLE (25 1650);
FORCEADD DNS..2
(-75 850);
PAINT RED (-75 850);
FORCEPROP 1 LAST COMMENT_BODY TRUE
J 0
(-75 850);
DISPLAY INVISIBLE (-75 850);
FORCEPROP 2 LAST CDS_LIB mstr_misc
J 0
(-75 850);
DISPLAY INVISIBLE (-75 850);
FORCEADD DNS..2
(0 -275);
PAINT RED (0 -275);
FORCEPROP 1 LAST COMMENT_BODY TRUE
J 0
(0 -275);
DISPLAY INVISIBLE (0 -275);
FORCEPROP 2 LAST CDS_LIB mstr_misc
J 0
(0 -275);
DISPLAY INVISIBLE (0 -275);
FORCEADD DNS..2
(2600 2025);
PAINT RED (2600 2025);
FORCEPROP 1 LAST COMMENT_BODY TRUE
J 0
(2600 2025);
DISPLAY INVISIBLE (2600 2025);
FORCEPROP 2 LAST CDS_LIB mstr_misc
J 0
(2600 2025);
DISPLAY INVISIBLE (2600 2025);
FORCEADD DNS..2
(2575 825);
PAINT RED (2575 825);
FORCEPROP 1 LAST COMMENT_BODY TRUE
J 0
(2575 825);
DISPLAY INVISIBLE (2575 825);
FORCEPROP 2 LAST CDS_LIB mstr_misc
J 0
(2575 825);
DISPLAY INVISIBLE (2575 825);
FORCEADD DNS..2
(0 3250);
PAINT RED (0 3250);
FORCEPROP 1 LAST COMMENT_BODY TRUE
J 0
(0 3250);
DISPLAY INVISIBLE (0 3250);
FORCEPROP 2 LAST CDS_LIB mstr_misc
J 0
(0 3250);
DISPLAY INVISIBLE (0 3250);
WIRE 16 -1 (2525 2600)(2525 2525);
WIRE 16 -1 (2625 1475)(2625 1400);
WIRE 16 -1 (2625 225)(2625 150);
WIRE 16 -1 (1625 875)(1625 800);
WIRE 16 -1 (1500 -375)(1500 -500);
WIRE 16 -1 (2575 1050)(2575 950);
WIRE 16 -1 (-50 300)(-50 275);
WIRE 16 -1 (-75 1075)(-75 975);
WIRE 16 -1 (2225 -1525)(2225 -1600);
WIRE 16 -1 (0 -50)(0 -150);
WIRE 16 -1 (2650 -900)(2650 -975);
WIRE 16 -1 (2650 -125)(2650 -225);
WIRE 16 -1 (25 -825)(25 -850);
WIRE 16 -1 (2000 -2200)(2000 -2300);
WIRE 16 -1 (650 -1300)(650 -1475);
WIRE 16 -1 (2950 -1350)(2950 -1525);
WIRE 16 -1 (0 3475)(0 3375);
WIRE 16 -1 (25 2650)(25 2700);
WIRE 16 -1 (0 2350)(0 2250);
WIRE 16 -1 (25 1550)(25 1575);
WIRE 16 -1 (1500 2025)(1500 1900);
WIRE 16 -1 (2500 3425)(2500 3325);
WIRE 16 -1 (2600 2250)(2600 2150);
WIRE 16 -1 (1625 3275)(1625 3200);
WIRE 16 -1 (4075 1875)(3025 1875);
FORCEPROP 2 LAST SIG_NAME RST_SWB_BIC_BUF_N
J 0
(3340 1885);
DISPLAY 0.808511 (3340 1885);
WIRE 16 -1 (2625 425)(2625 600);
WIRE 16 -1 (2625 600)(2725 600);
WIRE 16 -1 (2575 600)(2625 600);
WIRE 16 -1 (2575 750)(2575 600);
WIRE 16 -1 (2575 600)(1850 600);
FORCEPROP 2 LAST SIG_NAME FM_GPU_PWR_EN_R1
J 0
(1890 610);
DISPLAY 0.808511 (1890 610);
FORCEPROP 2 LASTPROP $XRERR UNIQUE?
J 0
(1650 610);
DISPLAY 0.638298 (1650 610);
PAINT MONO (1650 610);
DISPLAY INVISIBLE (1650 610);
WIRE 16 -1 (1850 600)(1850 175);
WIRE 16 -1 (3300 -1950)(4150 -1950);
FORCEPROP 2 LAST SIG_NAME UART_BMC_BIC_BUF_RX
J 0
(3490 -1940);
DISPLAY 0.723404 (3490 -1940);
PAINT WHITE (3490 -1940);
WIRE 16 -1 (1500 2875)(1500 3575);
WIRE 16 -1 (1625 3575)(1500 3575);
WIRE 16 -1 (1625 3650)(1625 3575);
WIRE 16 -1 (1625 3575)(1625 3475);
WIRE 16 -1 (2000 -1700)(2000 -1225);
WIRE 16 -1 (2225 -1225)(2000 -1225);
WIRE 16 -1 (2225 -1150)(2225 -1225);
WIRE 16 -1 (2225 -1225)(2225 -1325);
WIRE 16 -1 (1500 475)(1500 1175);
WIRE 16 -1 (1625 1175)(1500 1175);
WIRE 16 -1 (1625 1250)(1625 1175);
WIRE 16 -1 (1625 1175)(1625 1075);
WIRE 16 -1 (1075 -2000)(1750 -2000);
FORCEPROP 2 LAST SIG_NAME FM_UART_EN
J 0
(1190 -1990);
DISPLAY 0.723404 (1190 -1990);
PAINT WHITE (1190 -1990);
FORCEPROP 2 LASTPROP $XRERR UNIQUE?
J 0
(950 -1990);
DISPLAY 0.638298 (950 -1990);
PAINT MONO (950 -1990);
DISPLAY INVISIBLE (950 -1990);
WIRE 16 -1 (1075 -1900)(1750 -1900);
FORCEPROP 2 LAST SIG_NAME UART_BMC_BIC_R_RX
J 0
(1190 -1890);
DISPLAY 0.638298 (1190 -1890);
PAINT WHITE (1190 -1890);
FORCEPROP 2 LASTPROP $XRERR UNIQUE?
J 0
(950 -1890);
DISPLAY 0.638298 (950 -1890);
PAINT MONO (950 -1890);
DISPLAY INVISIBLE (950 -1890);
WIRE 16 -1 (3100 -1950)(2950 -1950);
WIRE 16 -1 (2950 -1725)(2950 -1950);
WIRE 16 -1 (2950 -1950)(2250 -1950);
FORCEPROP 2 LAST SIG_NAME UART_BMC_BIC_R_BUF_RX
J 0
(2315 -1940);
DISPLAY 0.638298 (2315 -1940);
PAINT WHITE (2315 -1940);
FORCEPROP 2 LASTPROP $XRERR UNIQUE?
J 0
(2075 -1940);
DISPLAY 0.638298 (2075 -1940);
PAINT MONO (2075 -1940);
DISPLAY INVISIBLE (2075 -1940);
WIRE 16 -1 (0 1875)(-150 1875);
WIRE 16 -1 (0 2050)(0 1875);
WIRE 16 -1 (25 1875)(0 1875);
WIRE 16 -1 (25 1875)(1100 1875);
FORCEPROP 2 LAST SIG_NAME RST_SWB_BIC_R_N
J 0
(65 1885);
DISPLAY 0.808511 (65 1885);
WIRE 16 -1 (25 1775)(25 1875);
WIRE 16 -1 (1100 2325)(1100 1875);
WIRE 16 -1 (0 3000)(-200 3000);
WIRE 16 -1 (0 3175)(0 3000);
WIRE 16 -1 (25 3000)(0 3000);
WIRE 16 -1 (1100 3000)(25 3000);
FORCEPROP 2 LAST SIG_NAME BMC_MONITER_R
J 0
(65 3010);
DISPLAY 0.808511 (65 3010);
WIRE 16 -1 (25 2900)(25 3000);
WIRE 16 -1 (1100 3000)(1100 2575);
WIRE 16 -1 (650 -1675)(650 -1900);
WIRE 16 -1 (650 -1900)(875 -1900);
WIRE 16 -1 (0 -1900)(650 -1900);
FORCEPROP 2 LAST SIG_NAME UART_BMC_BIC_RX
J 0
(40 -1890);
DISPLAY 0.723404 (40 -1890);
PAINT WHITE (40 -1890);
WIRE 16 -1 (0 -2000)(875 -2000);
FORCEPROP 2 LAST SIG_NAME FM_PDB_BUF_EN_R1
J 0
(40 -1990);
DISPLAY 0.723404 (40 -1990);
PAINT WHITE (40 -1990);
WIRE 16 -1 (0 -525)(-150 -525);
WIRE 16 -1 (0 -350)(0 -525);
WIRE 16 -1 (25 -525)(0 -525);
WIRE 16 -1 (25 -525)(1100 -525);
FORCEPROP 2 LAST SIG_NAME GPU_FPGA_RST_R_N
J 0
(65 -515);
DISPLAY 0.808511 (65 -515);
WIRE 16 -1 (25 -625)(25 -525);
WIRE 16 -1 (1100 -75)(1100 -525);
WIRE 16 -1 (2650 -425)(2650 -525);
WIRE 16 -1 (2650 -525)(2800 -525);
WIRE 16 -1 (2650 -700)(2650 -525);
WIRE 16 -1 (1850 -525)(2650 -525);
FORCEPROP 2 LAST SIG_NAME GPU_FPGA_RST_R1_BUF_N
J 0
(1840 -515);
DISPLAY 0.808511 (1840 -515);
FORCEPROP 2 LASTPROP $XRERR UNIQUE?
J 0
(1600 -515);
DISPLAY 0.638298 (1600 -515);
PAINT MONO (1600 -515);
DISPLAY INVISIBLE (1600 -515);
WIRE 16 -1 (1850 -525)(1850 -75);
WIRE 16 -1 (2525 2800)(2525 3000);
WIRE 16 -1 (2525 3000)(2750 3000);
WIRE 16 -1 (2500 3000)(2525 3000);
WIRE 16 -1 (2500 3125)(2500 3000);
WIRE 16 -1 (1850 3000)(2500 3000);
FORCEPROP 2 LAST SIG_NAME BMC_MONITER_BUF_R
J 0
(1865 3010);
DISPLAY 0.638298 (1865 3010);
FORCEPROP 2 LASTPROP $XRERR UNIQUE?
J 0
(1625 3010);
DISPLAY 0.638298 (1625 3010);
PAINT MONO (1625 3010);
DISPLAY INVISIBLE (1625 3010);
WIRE 16 -1 (1850 3000)(1850 2575);
WIRE 16 -1 (4075 3000)(2950 3000);
FORCEPROP 2 LAST SIG_NAME BMC_MONITER_BUF
J 0
(3265 3010);
DISPLAY 0.808511 (3265 3010);
WIRE 16 -1 (1100 600)(1100 175);
WIRE 16 -1 (-50 600)(1100 600);
FORCEPROP 2 LAST SIG_NAME FM_GPU_PWR_EN_R
J 0
(65 610);
DISPLAY 0.808511 (65 610);
WIRE 16 -1 (-75 600)(-50 600);
WIRE 16 -1 (-50 500)(-50 600);
WIRE 16 -1 (-75 600)(-75 775);
WIRE 16 -1 (-200 600)(-75 600);
WIRE 16 -1 (3000 -525)(3925 -525);
FORCEPROP 2 LAST SIG_NAME GPU_FPGA_RST_R_BUF_N
J 0
(3165 -515);
DISPLAY 0.808511 (3165 -515);
WIRE 16 -1 (3875 600)(2925 600);
FORCEPROP 2 LAST SIG_NAME FM_GPU_PWR_EN_R_BUF
J 0
(3115 610);
DISPLAY 0.808511 (3115 610);
WIRE 16 -1 (2625 1675)(2625 1875);
WIRE 16 -1 (2625 1875)(2825 1875);
WIRE 16 -1 (2600 1875)(2625 1875);
WIRE 16 -1 (2600 1950)(2600 1875);
WIRE 16 -1 (1850 1875)(2600 1875);
FORCEPROP 2 LAST SIG_NAME RST_SWB_BIC_BUF_R_N
J 0
(1865 1885);
DISPLAY 0.638298 (1865 1885);
FORCEPROP 2 LASTPROP $XRERR UNIQUE?
J 0
(1625 1885);
DISPLAY 0.638298 (1625 1885);
PAINT MONO (1625 1885);
DISPLAY INVISIBLE (1625 1885);
WIRE 16 -1 (1850 1875)(1850 2325);
DOT 1 (2600 1875);
DOT 1 (2950 -1950);
DOT 1 (650 -1900);
DOT 1 (2225 -1225);
DOT 1 (2525 3000);
DOT 1 (2500 3000);
DOT 1 (2625 1875);
DOT 1 (2625 600);
DOT 1 (2575 600);
DOT 1 (1625 3575);
DOT 1 (25 3000);
DOT 1 (1625 1175);
DOT 1 (25 1875);
DOT 1 (2650 -525);
DOT 1 (25 -525);
DOT 1 (0 3000);
DOT 1 (0 1875);
DOT 1 (-50 600);
DOT 1 (-75 600);
DOT 1 (0 -525);
FORCENOTE
PUSH-PULL OUTPUT
(1150 -850) 0;
DISPLAY LEFT (1150 -850);
DISPLAY 1.021277 (1150 -850);
PAINT WHITE (1150 -850);
FORCENOTE
PUSH-PULL OUTPUT
(1100 1500) 0;
DISPLAY LEFT (1100 1500);
DISPLAY 1.021277 (1100 1500);
PAINT WHITE (1100 1500);
QUIT
